FILE_TYPE = MACRO_DRAWING;
SET COLOR_WIRE YELLOW;
SET COLOR_PROP MONO;
SET COLOR_DOT WHITE;
SET COLOR_ARC YELLOW;
SET COLOR_BODY GREEN;
SET COLOR_NOTE MONO;
SET PROP_DISPLAY VALUE;
SET PAGE_NUMBER P219;
FORCEADD PVDDQ_DEF..1
(4450 1925);
FORCEPROP 3 LASTPIN (4450 1875) SIG_NAME PVDDQ_DEF\g
J 0
(4460 1885);
DISPLAY 0.659574 (4460 1885);
PAINT MONO (4460 1885);
DISPLAY INVISIBLE (4460 1885);
FORCEPROP 1 LAST HDL_POWER PVDDQ_DEF
J 1
(4450 1975);
DISPLAY 0.872340 (4450 1975);
PAINT GREEN (4450 1975);
DISPLAY INVISIBLE (4450 1975);
FORCEPROP 1 LAST BODY_TYPE PLUMBING
J 0
(4405 1882);
DISPLAY 0.340426 (4405 1882);
PAINT GREEN (4405 1882);
DISPLAY INVISIBLE (4405 1882);
FORCEPROP 2 LAST CDS_LIB mstr_symbols
J 0
(4450 1925);
PAINT ORANGE (4450 1925);
DISPLAY INVISIBLE (4450 1925);
FORCEPROP 1 LAST VOLTAGE 1.2V
J 0
(4405 1882);
DISPLAY 0.340426 (4405 1882);
PAINT SKYBLUE (4405 1882);
DISPLAY INVISIBLE (4405 1882);
FORCEPROP 1 LAST PATH I1
J 0
(4500 1950);
DISPLAY 0.872340 (4500 1950);
PAINT AQUA (4500 1950);
DISPLAY INVISIBLE (4500 1950);
FORCEADD IR354XX..1
(1750 2125);
FORCEPROP 2 LASTPIN (1250 2575) $PN 25
J 2
(1240 2585);
DISPLAY 0.617021 (1240 2585);
PAINT ORANGE (1240 2585);
FORCEPROP 2 LASTPIN (1250 1775) $PN 32
J 2
(1240 1785);
DISPLAY 0.617021 (1240 1785);
PAINT ORANGE (1240 1785);
FORCEPROP 2 LASTPIN (2250 2425) $PN 31
J 0
(2260 2435);
DISPLAY 0.617021 (2260 2435);
PAINT ORANGE (2260 2435);
FORCEPROP 2 LASTPIN (2250 2175) $PN 36
J 0
(2260 2185);
DISPLAY 0.617021 (2260 2185);
PAINT ORANGE (2260 2185);
FORCEPROP 2 LASTPIN (2250 1575) $PN 5
J 0
(2260 1585);
DISPLAY 0.617021 (2260 1585);
PAINT ORANGE (2260 1585);
FORCEPROP 2 LASTPIN (1250 1925) $PN 39
J 2
(1240 1935);
DISPLAY 0.617021 (1240 1935);
PAINT ORANGE (1240 1935);
FORCEPROP 2 LASTPIN (1250 2375) $PN 35
J 2
(1240 2385);
DISPLAY 0.617021 (1240 2385);
PAINT ORANGE (1240 2385);
FORCEPROP 2 LASTPIN (1250 2125) $PN 6
J 2
(1240 2135);
DISPLAY 0.617021 (1240 2135);
PAINT ORANGE (1240 2135);
FORCEPROP 2 LASTPIN (1250 2675) $PN 3
J 2
(1240 2685);
DISPLAY 0.617021 (1240 2685);
PAINT ORANGE (1240 2685);
FORCEPROP 2 LASTPIN (1250 2475) $PN 4
J 2
(1240 2485);
DISPLAY 0.617021 (1240 2485);
PAINT ORANGE (1240 2485);
FORCEPROP 2 LASTPIN (1250 2275) $PN 1
J 2
(1240 2285);
DISPLAY 0.617021 (1240 2285);
PAINT ORANGE (1240 2285);
FORCEPROP 2 LAST NO_XNET_CONNECTION 1
J 0
(1300 2975);
PAINT MONO (1300 2975);
FORCEPROP 1 LAST MATERIAL IC
J 0
(1300 2875);
DISPLAY 0.617021 (1300 2875);
PAINT SKYBLUE (1300 2875);
FORCEPROP 2 LASTPIN (2250 1825) $PN 10
J 0
(2260 1835);
DISPLAY 0.617021 (2260 1835);
PAINT ORANGE (2260 1835);
FORCEPROP 2 LASTPIN (2250 1675) $PN 40
J 0
(2260 1685);
DISPLAY 0.617021 (2260 1685);
PAINT ORANGE (2260 1685);
FORCEPROP 2 LASTPIN (2250 1625) $PN 7
J 0
(2260 1635);
DISPLAY 0.617021 (2260 1635);
PAINT ORANGE (2260 1635);
FORCEPROP 2 LASTPIN (2250 1725) $PN 2
J 0
(2260 1735);
DISPLAY 0.617021 (2260 1735);
PAINT ORANGE (2260 1735);
FORCEPROP 2 LASTPIN (2250 2475) $PN 37
J 0
(2260 2485);
DISPLAY 0.617021 (2260 2485);
PAINT ORANGE (2260 2485);
FORCEPROP 2 LASTPIN (1250 1825) $PN 33
J 2
(1240 1835);
DISPLAY 0.617021 (1240 1835);
PAINT ORANGE (1240 1835);
FORCEPROP 2 LASTPIN (2250 2675) $PN 38
J 0
(2260 2685);
DISPLAY 0.617021 (2260 2685);
PAINT ORANGE (2260 2685);
FORCEPROP 2 LASTPIN (1250 2625) $PN 30
J 2
(1240 2635);
DISPLAY 0.617021 (1240 2635);
PAINT ORANGE (1240 2635);
FORCEPROP 1 LAST PART_NUMBER H73688-001
J 0
(1350 1425);
DISPLAY 0.617021 (1350 1425);
PAINT BLUE (1350 1425);
FORCEPROP 2 LASTPIN (1250 2025) $PN 34
J 2
(1240 2035);
DISPLAY 0.617021 (1240 2035);
PAINT ORANGE (1240 2035);
FORCEPROP 2 LASTPIN (1250 2175) $PN 41
J 2
(1240 2185);
DISPLAY 0.617021 (1240 2185);
PAINT ORANGE (1240 2185);
FORCEPROP 1 LAST LOCATION EU7A1
J 0
(1300 2925);
DISPLAY 0.617021 (1300 2925);
PAINT AQUA (1300 2925);
FORCEPROP 1 LAST VALUE IR35411
J 1
(1750 2750);
DISPLAY 0.617021 (1750 2750);
PAINT SKYBLUE (1750 2750);
DISPLAY INVISIBLE (1750 2750);
FORCEPROP 2 LAST CDS_LOCATION EU7A1
J 0
(1300 2925);
PAINT GREEN (1300 2925);
DISPLAY INVISIBLE (1300 2925);
FORCEPROP 2 LAST SEC 1
J 0
(1300 2975);
DISPLAY 0.680851 (1300 2975);
PAINT MONO (1300 2975);
DISPLAY INVISIBLE (1300 2975);
FORCEPROP 2 LAST SEC_TYPE SM
J 0
(1300 2975);
DISPLAY 1.021277 (1300 2975);
PAINT ORANGE (1300 2975);
DISPLAY INVISIBLE (1300 2975);
FORCEPROP 1 LAST PACK_TYPE SM
J 0
(1300 2975);
PAINT SKYBLUE (1300 2975);
DISPLAY INVISIBLE (1300 2975);
FORCEPROP 1 LAST PATH I106
J 0
(1750 2875);
PAINT GREEN (1750 2875);
DISPLAY INVISIBLE (1750 2875);
FORCEPROP 2 LAST CDS_LIB mstr_discrete
J 0
(1750 2125);
PAINT ORANGE (1750 2125);
DISPLAY INVISIBLE (1750 2125);
FORCEADD IR354XX..1
(1775 -125);
FORCEPROP 2 LASTPIN (1275 125) $PN 35
J 2
(1265 135);
DISPLAY 0.617021 (1265 135);
PAINT ORANGE (1265 135);
FORCEPROP 2 LASTPIN (2275 -575) $PN 40
J 0
(2285 -565);
DISPLAY 0.617021 (2285 -565);
PAINT ORANGE (2285 -565);
FORCEPROP 0 LAST BOM_SS NOPOP
J 0
(1375 -875);
DISPLAY 0.638298 (1375 -875);
PAINT BROWN (1375 -875);
DISPLAY BOTH (1375 -875);
FORCEPROP 2 LASTPIN (2275 -525) $PN 2
J 0
(2285 -515);
DISPLAY 0.617021 (2285 -515);
PAINT ORANGE (2285 -515);
FORCEPROP 2 LASTPIN (2275 175) $PN 31
J 0
(2285 185);
DISPLAY 0.617021 (2285 185);
PAINT ORANGE (2285 185);
FORCEPROP 2 LASTPIN (2275 225) $PN 37
J 0
(2285 235);
DISPLAY 0.617021 (2285 235);
PAINT ORANGE (2285 235);
FORCEPROP 1 LAST PART_NUMBER H73688-001
J 0
(1400 -825);
DISPLAY 0.617021 (1400 -825);
PAINT BLUE (1400 -825);
FORCEPROP 2 LASTPIN (1275 -75) $PN 41
J 2
(1265 -65);
DISPLAY 0.617021 (1265 -65);
PAINT ORANGE (1265 -65);
FORCEPROP 2 LASTPIN (1275 325) $PN 25
J 2
(1265 335);
DISPLAY 0.617021 (1265 335);
PAINT ORANGE (1265 335);
FORCEPROP 2 LAST NO_XNET_CONNECTION 1
J 0
(1325 725);
PAINT MONO (1325 725);
FORCEPROP 2 LASTPIN (1275 425) $PN 3
J 2
(1265 435);
DISPLAY 0.617021 (1265 435);
PAINT ORANGE (1265 435);
FORCEPROP 2 LASTPIN (1275 25) $PN 1
J 2
(1265 35);
DISPLAY 0.617021 (1265 35);
PAINT ORANGE (1265 35);
FORCEPROP 2 LASTPIN (2275 -425) $PN 10
J 0
(2285 -415);
DISPLAY 0.617021 (2285 -415);
PAINT ORANGE (2285 -415);
FORCEPROP 2 LASTPIN (2275 -625) $PN 7
J 0
(2285 -615);
DISPLAY 0.617021 (2285 -615);
PAINT ORANGE (2285 -615);
FORCEPROP 2 LASTPIN (2275 -675) $PN 5
J 0
(2285 -665);
DISPLAY 0.617021 (2285 -665);
PAINT ORANGE (2285 -665);
FORCEPROP 2 LASTPIN (1275 -125) $PN 6
J 2
(1265 -115);
DISPLAY 0.617021 (1265 -115);
PAINT ORANGE (1265 -115);
FORCEPROP 2 LASTPIN (1275 -425) $PN 33
J 2
(1265 -415);
DISPLAY 0.617021 (1265 -415);
PAINT ORANGE (1265 -415);
FORCEPROP 2 LASTPIN (2275 -75) $PN 36
J 0
(2285 -65);
DISPLAY 0.617021 (2285 -65);
PAINT ORANGE (2285 -65);
FORCEPROP 2 LASTPIN (1275 -225) $PN 34
J 2
(1265 -215);
DISPLAY 0.617021 (1265 -215);
PAINT ORANGE (1265 -215);
FORCEPROP 2 LASTPIN (1275 225) $PN 4
J 2
(1265 235);
DISPLAY 0.617021 (1265 235);
PAINT ORANGE (1265 235);
FORCEPROP 2 LASTPIN (1275 -475) $PN 32
J 2
(1265 -465);
DISPLAY 0.617021 (1265 -465);
PAINT ORANGE (1265 -465);
FORCEPROP 1 LAST MATERIAL IC
J 0
(1325 625);
DISPLAY 0.617021 (1325 625);
PAINT SKYBLUE (1325 625);
FORCEPROP 2 LASTPIN (2275 425) $PN 38
J 0
(2285 435);
DISPLAY 0.617021 (2285 435);
PAINT ORANGE (2285 435);
FORCEPROP 2 LASTPIN (1275 375) $PN 30
J 2
(1265 385);
DISPLAY 0.617021 (1265 385);
PAINT ORANGE (1265 385);
FORCEPROP 1 LAST LOCATION EU7A4
J 0
(1325 675);
DISPLAY 0.617021 (1325 675);
PAINT AQUA (1325 675);
FORCEPROP 2 LASTPIN (1275 -325) $PN 39
J 2
(1265 -315);
DISPLAY 0.617021 (1265 -315);
PAINT ORANGE (1265 -315);
FORCEPROP 1 LAST PATH I107
J 0
(1775 625);
PAINT GREEN (1775 625);
DISPLAY INVISIBLE (1775 625);
FORCEPROP 1 LAST PACK_TYPE SM
J 0
(1325 725);
PAINT SKYBLUE (1325 725);
DISPLAY INVISIBLE (1325 725);
FORCEPROP 2 LAST SEC_TYPE SM
J 0
(1325 725);
DISPLAY 1.021277 (1325 725);
PAINT ORANGE (1325 725);
DISPLAY INVISIBLE (1325 725);
FORCEPROP 2 LAST SEC 1
J 0
(1325 725);
DISPLAY 0.680851 (1325 725);
PAINT MONO (1325 725);
DISPLAY INVISIBLE (1325 725);
FORCEPROP 2 LAST CDS_LOCATION EU7A4
J 0
(1325 675);
PAINT GREEN (1325 675);
DISPLAY INVISIBLE (1325 675);
FORCEPROP 2 LAST CDS_LIB mstr_discrete
J 0
(1775 -125);
PAINT ORANGE (1775 -125);
DISPLAY INVISIBLE (1775 -125);
FORCEPROP 1 LAST VALUE IR35411
J 1
(1775 500);
DISPLAY 0.617021 (1775 500);
PAINT SKYBLUE (1775 500);
DISPLAY INVISIBLE (1775 500);
FORCEADD RES..2
(4575 2300);
FORCEPROP 1 LAST WATTAGE 1/16W
J 0
(4615 2275);
DISPLAY 0.617021 (4615 2275);
PAINT SKYBLUE (4615 2275);
FORCEPROP 1 LAST MATERIAL EMPTY
J 0
(4615 2225);
DISPLAY 0.617021 (4615 2225);
PAINT RED (4615 2225);
FORCEPROP 1 LAST VALUE 68.1K
J 0
(4620 2375);
DISPLAY 0.617021 (4620 2375);
PAINT SKYBLUE (4620 2375);
FORCEPROP 1 LAST LOCATION R7A20
J 0
(4620 2425);
DISPLAY 0.617021 (4620 2425);
PAINT AQUA (4620 2425);
FORCEPROP 1 LAST PACK_TYPE 0402
J 0
(4615 2125);
DISPLAY 0.617021 (4615 2125);
PAINT SKYBLUE (4615 2125);
FORCEPROP 1 LAST PART_NUMBER G21796-187
J 0
(4615 2175);
DISPLAY 0.617021 (4615 2175);
PAINT BLUE (4615 2175);
FORCEPROP 1 LAST TOLERANCE 1%
J 0
(4620 2325);
DISPLAY 0.617021 (4620 2325);
PAINT SKYBLUE (4620 2325);
FORCEPROP 1 LASTPIN (4575 2200) $PN 2
J 0
(4580 2210);
DISPLAY 0.787234 (4580 2210);
PAINT ORANGE (4580 2210);
DISPLAY INVISIBLE (4580 2210);
FORCEPROP 2 LAST CDS_LIB mstr_discrete
J 0
(4575 2300);
PAINT ORANGE (4575 2300);
DISPLAY INVISIBLE (4575 2300);
FORCEPROP 1 LASTPIN (4575 2400) $PN 1
J 0
(4580 2362);
DISPLAY 0.787234 (4580 2362);
PAINT ORANGE (4580 2362);
DISPLAY INVISIBLE (4580 2362);
FORCEPROP 1 LAST PATH I108
J 0
(4625 2475);
DISPLAY 0.978723 (4625 2475);
PAINT WHITE (4625 2475);
DISPLAY INVISIBLE (4625 2475);
FORCEPROP 2 LAST $SEC 1
J 0
(4625 2525);
PAINT MONO (4625 2525);
DISPLAY INVISIBLE (4625 2525);
FORCEPROP 2 LAST CDS_SEC 1
J 0
(4625 2525);
PAINT MONO (4625 2525);
DISPLAY INVISIBLE (4625 2525);
FORCEADD GND..1
(4575 2125);
FORCEPROP 3 LASTPIN (4575 2175) SIG_NAME GND\g
J 0
(4585 2185);
DISPLAY 0.659574 (4585 2185);
PAINT MONO (4585 2185);
DISPLAY INVISIBLE (4585 2185);
FORCEPROP 1 LAST VOLTAGE 0
J 0
(4575 2125);
PAINT SKYBLUE (4575 2125);
DISPLAY INVISIBLE (4575 2125);
FORCEPROP 1 LAST SIZE 1B
J 0
(4650 2075);
DISPLAY 1.723404 (4650 2075);
PAINT GREEN (4650 2075);
DISPLAY INVISIBLE (4650 2075);
FORCEPROP 2 LAST CDS_LIB mstr_symbols
J 0
(4575 2125);
PAINT ORANGE (4575 2125);
DISPLAY INVISIBLE (4575 2125);
FORCEPROP 1 LAST PATH I109
J 0
(4650 2125);
DISPLAY 0.872340 (4650 2125);
PAINT AQUA (4650 2125);
DISPLAY INVISIBLE (4650 2125);
FORCEPROP 2 LAST BOM_COST PROC_VRD_VCCIN_CPU0
J 0
(4200 2200);
DISPLAY 1.446809 (4200 2200);
PAINT MONO (4200 2200);
DISPLAY INVISIBLE (4200 2200);
FORCEPROP 2 LAST ROOM PVCCIN_CPU0_PWR_VR
J 0
(4025 2200);
DISPLAY 1.936170 (4025 2200);
PAINT ORANGE (4025 2200);
DISPLAY INVISIBLE (4025 2200);
FORCEPROP 1 LAST BODY_TYPE PLUMBING
J 0
(4530 2082);
DISPLAY 0.340426 (4530 2082);
PAINT GREEN (4530 2082);
DISPLAY INVISIBLE (4530 2082);
FORCEPROP 1 LAST HDL_POWER GND
J 0
(4575 2275);
DISPLAY 1.723404 (4575 2275);
PAINT GREEN (4575 2275);
DISPLAY INVISIBLE (4575 2275);
FORCEADD RES..2
(4575 25);
FORCEPROP 0 LAST BOM_SS NOPOP
J 0
(4600 -200);
DISPLAY 0.638298 (4600 -200);
PAINT BROWN (4600 -200);
DISPLAY BOTH (4600 -200);
FORCEPROP 1 LAST LOCATION R7A21
J 0
(4620 150);
DISPLAY 0.617021 (4620 150);
PAINT AQUA (4620 150);
FORCEPROP 1 LAST VALUE 68.1K
J 0
(4620 100);
DISPLAY 0.617021 (4620 100);
PAINT SKYBLUE (4620 100);
FORCEPROP 1 LAST WATTAGE 1/16W
J 0
(4615 0);
DISPLAY 0.617021 (4615 0);
PAINT SKYBLUE (4615 0);
FORCEPROP 1 LAST MATERIAL EMPTY
J 0
(4615 -50);
DISPLAY 0.617021 (4615 -50);
PAINT RED (4615 -50);
FORCEPROP 1 LAST PACK_TYPE 0402
J 0
(4615 -150);
DISPLAY 0.617021 (4615 -150);
PAINT SKYBLUE (4615 -150);
FORCEPROP 1 LASTPIN (4575 125) $PN 1
J 0
(4580 87);
DISPLAY 0.787234 (4580 87);
PAINT ORANGE (4580 87);
FORCEPROP 1 LASTPIN (4575 -75) $PN 2
J 0
(4580 -65);
DISPLAY 0.787234 (4580 -65);
PAINT ORANGE (4580 -65);
FORCEPROP 1 LAST TOLERANCE 1%
J 0
(4620 50);
DISPLAY 0.617021 (4620 50);
PAINT SKYBLUE (4620 50);
FORCEPROP 1 LAST PART_NUMBER G21796-187
J 0
(4615 -100);
DISPLAY 0.617021 (4615 -100);
PAINT BLUE (4615 -100);
FORCEPROP 2 LAST SEC_TYPE 0402
J 0
(4625 250);
DISPLAY 1.021277 (4625 250);
PAINT ORANGE (4625 250);
DISPLAY INVISIBLE (4625 250);
FORCEPROP 2 LAST SEC 1
J 0
(4625 250);
PAINT MONO (4625 250);
DISPLAY INVISIBLE (4625 250);
FORCEPROP 1 LAST PATH I110
J 0
(4625 200);
DISPLAY 0.978723 (4625 200);
PAINT WHITE (4625 200);
DISPLAY INVISIBLE (4625 200);
FORCEPROP 2 LAST CDS_LIB mstr_discrete
J 0
(4575 25);
PAINT ORANGE (4575 25);
DISPLAY INVISIBLE (4575 25);
FORCEADD GND..1
(4575 -175);
FORCEPROP 3 LASTPIN (4575 -125) SIG_NAME GND\g
J 0
(4585 -115);
DISPLAY 0.659574 (4585 -115);
PAINT MONO (4585 -115);
DISPLAY INVISIBLE (4585 -115);
FORCEPROP 1 LAST VOLTAGE 0
J 0
(4575 -175);
PAINT SKYBLUE (4575 -175);
DISPLAY INVISIBLE (4575 -175);
FORCEPROP 1 LAST SIZE 1B
J 0
(4650 -225);
DISPLAY 1.723404 (4650 -225);
PAINT GREEN (4650 -225);
DISPLAY INVISIBLE (4650 -225);
FORCEPROP 2 LAST CDS_LIB mstr_symbols
J 0
(4575 -175);
PAINT ORANGE (4575 -175);
DISPLAY INVISIBLE (4575 -175);
FORCEPROP 1 LAST PATH I111
J 0
(4650 -175);
DISPLAY 0.872340 (4650 -175);
PAINT AQUA (4650 -175);
DISPLAY INVISIBLE (4650 -175);
FORCEPROP 2 LAST BOM_COST PROC_VRD_VCCIN_CPU0
J 0
(4200 -100);
DISPLAY 1.446809 (4200 -100);
PAINT MONO (4200 -100);
DISPLAY INVISIBLE (4200 -100);
FORCEPROP 2 LAST ROOM PVCCIN_CPU0_PWR_VR
J 0
(4025 -100);
DISPLAY 1.936170 (4025 -100);
PAINT ORANGE (4025 -100);
DISPLAY INVISIBLE (4025 -100);
FORCEPROP 1 LAST BODY_TYPE PLUMBING
J 0
(4530 -218);
DISPLAY 0.340426 (4530 -218);
PAINT GREEN (4530 -218);
DISPLAY INVISIBLE (4530 -218);
FORCEPROP 1 LAST HDL_POWER GND
J 0
(4575 -25);
DISPLAY 1.723404 (4575 -25);
PAINT GREEN (4575 -25);
DISPLAY INVISIBLE (4575 -25);
FORCEADD P5V_STBY..1
(225 3150);
FORCEPROP 3 LASTPIN (225 3100) SIG_NAME P5V_STBY\g
J 0
(235 3110);
DISPLAY 0.659574 (235 3110);
PAINT MONO (235 3110);
DISPLAY INVISIBLE (235 3110);
FORCEPROP 1 LAST HDL_POWER P5V_STBY
J 0
(-75 3025);
DISPLAY 0.872340 (-75 3025);
PAINT ORANGE (-75 3025);
DISPLAY INVISIBLE (-75 3025);
FORCEPROP 1 LAST BODY_TYPE PLUMBING
J 0
(180 3107);
DISPLAY 0.340426 (180 3107);
PAINT GREEN (180 3107);
DISPLAY INVISIBLE (180 3107);
FORCEPROP 1 LAST VOLTAGE 5.0V
J 0
(180 3107);
DISPLAY 0.340426 (180 3107);
PAINT SKYBLUE (180 3107);
DISPLAY INVISIBLE (180 3107);
FORCEPROP 2 LAST CDS_LIB mstr_symbols
J 0
(225 3150);
PAINT ORANGE (225 3150);
DISPLAY INVISIBLE (225 3150);
FORCEPROP 1 LAST SIZE 1B
J 0
(270 3172);
DISPLAY 0.340426 (270 3172);
PAINT GREEN (270 3172);
DISPLAY INVISIBLE (270 3172);
FORCEPROP 1 LAST PATH I112
J 0
(270 3152);
DISPLAY 0.340426 (270 3152);
PAINT GREEN (270 3152);
DISPLAY INVISIBLE (270 3152);
FORCEADD CAP_A..1
(1075 -625);
FORCEPROP 1 LAST VOLTAGE 16V
J 0
(1125 -625);
DISPLAY 0.617021 (1125 -625);
PAINT SKYBLUE (1125 -625);
FORCEPROP 1 LAST TOLERANCE 10%
J 0
(1125 -675);
DISPLAY 0.617021 (1125 -675);
PAINT SKYBLUE (1125 -675);
FORCEPROP 1 LAST MATERIAL X7R
J 0
(1125 -725);
DISPLAY 0.617021 (1125 -725);
PAINT SKYBLUE (1125 -725);
FORCEPROP 1 LAST PACK_TYPE 0402V
J 0
(1125 -825);
DISPLAY 0.617021 (1125 -825);
PAINT SKYBLUE (1125 -825);
FORCEPROP 0 LAST POP NOPOP
J 0
(1139 -888);
DISPLAY 1.021277 (1139 -888);
PAINT RED (1139 -888);
FORCEPROP 0 LAST BOM_SS NOPOP
J 0
(1200 -950);
DISPLAY 0.638298 (1200 -950);
PAINT BROWN (1200 -950);
DISPLAY BOTH (1200 -950);
FORCEPROP 1 LAST VALUE 0.1UF
J 0
(1125 -575);
DISPLAY 0.617021 (1125 -575);
PAINT SKYBLUE (1125 -575);
FORCEPROP 1 LASTPIN (1075 -525) $PN 1
J 0
(1085 -545);
DISPLAY 0.787234 (1085 -545);
PAINT ORANGE (1085 -545);
FORCEPROP 1 LASTPIN (1075 -725) $PN 2
J 0
(1085 -745);
DISPLAY 0.787234 (1085 -745);
PAINT ORANGE (1085 -745);
FORCEPROP 1 LAST PART_NUMBER A36096-030
J 0
(1125 -775);
DISPLAY 0.617021 (1125 -775);
PAINT BLUE (1125 -775);
FORCEPROP 1 LAST LOCATION CT46
J 0
(925 -625);
DISPLAY 0.617021 (925 -625);
PAINT AQUA (925 -625);
FORCEPROP 2 LAST SEC_TYPE 0402V
J 0
(1125 -425);
DISPLAY 1.021277 (1125 -425);
PAINT ORANGE (1125 -425);
DISPLAY INVISIBLE (1125 -425);
FORCEPROP 0 LAST SEC 1
J 0
(1125 -525);
DISPLAY 0.680851 (1125 -525);
PAINT MONO (1125 -525);
DISPLAY INVISIBLE (1125 -525);
FORCEPROP 2 LAST CDS_LIB dev_discrete
J 0
(1075 -625);
PAINT MONO (1075 -625);
DISPLAY INVISIBLE (1075 -625);
FORCEPROP 1 LAST PATH I113
J 0
(1125 -475);
DISPLAY 0.978723 (1125 -475);
PAINT WHITE (1125 -475);
DISPLAY INVISIBLE (1125 -475);
FORCEPROP 2 LAST ROOM PVCCIN_CPU0_PWR_VR
J 0
(1125 -475);
DISPLAY 1.361702 (1125 -475);
PAINT ORANGE (1125 -475);
DISPLAY INVISIBLE (1125 -475);
FORCEADD GND..1
(1075 -900);
FORCEPROP 3 LASTPIN (1075 -850) SIG_NAME GND\g
J 0
(1085 -840);
DISPLAY 0.659574 (1085 -840);
PAINT MONO (1085 -840);
DISPLAY INVISIBLE (1085 -840);
FORCEPROP 2 LAST CDS_LIB mstr_symbols
J 0
(1075 -900);
PAINT MONO (1075 -900);
DISPLAY INVISIBLE (1075 -900);
FORCEPROP 1 LAST PATH I114
J 0
(1150 -900);
DISPLAY 0.872340 (1150 -900);
PAINT AQUA (1150 -900);
DISPLAY INVISIBLE (1150 -900);
FORCEPROP 2 LAST ROOM PVCCIN_CPU0_PWR_VR
J 0
(525 -825);
DISPLAY 1.936170 (525 -825);
PAINT ORANGE (525 -825);
DISPLAY INVISIBLE (525 -825);
FORCEPROP 2 LAST BOM_COST PROC_VRD_VCCIN_CPU0
J 0
(700 -825);
DISPLAY 1.446809 (700 -825);
PAINT MONO (700 -825);
DISPLAY INVISIBLE (700 -825);
FORCEPROP 1 LAST SIZE 1B
J 0
(1150 -950);
DISPLAY 1.723404 (1150 -950);
PAINT GREEN (1150 -950);
DISPLAY INVISIBLE (1150 -950);
FORCEPROP 1 LAST VOLTAGE 0
J 0
(1075 -900);
PAINT SKYBLUE (1075 -900);
DISPLAY INVISIBLE (1075 -900);
FORCEPROP 1 LAST BODY_TYPE PLUMBING
J 0
(1030 -943);
DISPLAY 0.340426 (1030 -943);
PAINT GREEN (1030 -943);
DISPLAY INVISIBLE (1030 -943);
FORCEPROP 1 LAST HDL_POWER GND
J 0
(1075 -750);
DISPLAY 1.723404 (1075 -750);
PAINT GREEN (1075 -750);
DISPLAY INVISIBLE (1075 -750);
FORCEADD CAP_A..1
(1025 1625);
FORCEPROP 1 LAST PACK_TYPE 0402V
J 0
(1075 1425);
DISPLAY 0.617021 (1075 1425);
PAINT SKYBLUE (1075 1425);
FORCEPROP 1 LAST TOLERANCE 10%
J 0
(1075 1575);
DISPLAY 0.617021 (1075 1575);
PAINT SKYBLUE (1075 1575);
FORCEPROP 1 LAST MATERIAL X7R
J 0
(1075 1525);
DISPLAY 0.617021 (1075 1525);
PAINT SKYBLUE (1075 1525);
FORCEPROP 1 LAST VALUE 0.1UF
J 0
(1075 1675);
DISPLAY 0.617021 (1075 1675);
PAINT SKYBLUE (1075 1675);
FORCEPROP 1 LAST VOLTAGE 16V
J 0
(1075 1625);
DISPLAY 0.617021 (1075 1625);
PAINT SKYBLUE (1075 1625);
FORCEPROP 1 LASTPIN (1025 1525) $PN 2
J 0
(1035 1505);
DISPLAY 0.787234 (1035 1505);
PAINT ORANGE (1035 1505);
FORCEPROP 1 LASTPIN (1025 1725) $PN 1
J 0
(1035 1705);
DISPLAY 0.787234 (1035 1705);
PAINT ORANGE (1035 1705);
FORCEPROP 1 LAST LOCATION CT45
J 0
(875 1625);
DISPLAY 0.617021 (875 1625);
PAINT AQUA (875 1625);
FORCEPROP 1 LAST PART_NUMBER A36096-030
J 0
(1075 1475);
DISPLAY 0.617021 (1075 1475);
PAINT BLUE (1075 1475);
FORCEPROP 0 LAST POP NOPOP
J 0
(1084 1364);
DISPLAY 1.021277 (1084 1364);
PAINT RED (1084 1364);
FORCEPROP 2 LAST ROOM PVCCIN_CPU0_PWR_VR
J 0
(1075 1775);
DISPLAY 1.361702 (1075 1775);
PAINT ORANGE (1075 1775);
DISPLAY INVISIBLE (1075 1775);
FORCEPROP 1 LAST PATH I116
J 0
(1075 1775);
DISPLAY 0.978723 (1075 1775);
PAINT WHITE (1075 1775);
DISPLAY INVISIBLE (1075 1775);
FORCEPROP 2 LAST CDS_LIB dev_discrete
J 0
(1025 1625);
PAINT MONO (1025 1625);
DISPLAY INVISIBLE (1025 1625);
FORCEPROP 0 LAST SEC 1
J 0
(1075 1725);
DISPLAY 0.680851 (1075 1725);
PAINT MONO (1075 1725);
DISPLAY INVISIBLE (1075 1725);
FORCEPROP 2 LAST SEC_TYPE 0402V
J 0
(1075 1825);
DISPLAY 1.021277 (1075 1825);
PAINT ORANGE (1075 1825);
DISPLAY INVISIBLE (1075 1825);
FORCEADD GND..1
(1025 1375);
FORCEPROP 3 LASTPIN (1025 1425) SIG_NAME GND\g
J 0
(1035 1435);
DISPLAY 0.659574 (1035 1435);
PAINT MONO (1035 1435);
DISPLAY INVISIBLE (1035 1435);
FORCEPROP 1 LAST HDL_POWER GND
J 0
(1025 1525);
DISPLAY 1.723404 (1025 1525);
PAINT GREEN (1025 1525);
DISPLAY INVISIBLE (1025 1525);
FORCEPROP 1 LAST BODY_TYPE PLUMBING
J 0
(980 1332);
DISPLAY 0.340426 (980 1332);
PAINT GREEN (980 1332);
DISPLAY INVISIBLE (980 1332);
FORCEPROP 2 LAST CDS_LIB mstr_symbols
J 0
(1025 1375);
PAINT MONO (1025 1375);
DISPLAY INVISIBLE (1025 1375);
FORCEPROP 1 LAST PATH I117
J 0
(1100 1375);
DISPLAY 0.872340 (1100 1375);
PAINT AQUA (1100 1375);
DISPLAY INVISIBLE (1100 1375);
FORCEPROP 2 LAST ROOM PVCCIN_CPU0_PWR_VR
J 0
(475 1450);
DISPLAY 1.936170 (475 1450);
PAINT ORANGE (475 1450);
DISPLAY INVISIBLE (475 1450);
FORCEPROP 2 LAST BOM_COST PROC_VRD_VCCIN_CPU0
J 0
(650 1450);
DISPLAY 1.446809 (650 1450);
PAINT MONO (650 1450);
DISPLAY INVISIBLE (650 1450);
FORCEPROP 1 LAST SIZE 1B
J 0
(1100 1325);
DISPLAY 1.723404 (1100 1325);
PAINT GREEN (1100 1325);
DISPLAY INVISIBLE (1100 1325);
FORCEPROP 1 LAST VOLTAGE 0
J 0
(1025 1375);
PAINT SKYBLUE (1025 1375);
DISPLAY INVISIBLE (1025 1375);
FORCEADD CAP..1
(3075 -100);
FORCEPROP 1 LAST VALUE 1000PF
J 0
(3125 -50);
DISPLAY 0.617021 (3125 -50);
PAINT SKYBLUE (3125 -50);
FORCEPROP 1 LAST VOLTAGE 50V
J 0
(3125 -100);
DISPLAY 0.617021 (3125 -100);
PAINT SKYBLUE (3125 -100);
FORCEPROP 1 LASTPIN (3075 0) $PN 1
J 0
(3085 -20);
DISPLAY 0.787234 (3085 -20);
PAINT ORANGE (3085 -20);
FORCEPROP 0 LAST POP NOPOP
J 0
(3125 0);
DISPLAY 1.021277 (3125 0);
PAINT RED (3125 0);
FORCEPROP 1 LAST TOLERANCE 10%
J 0
(3125 -150);
DISPLAY 0.617021 (3125 -150);
PAINT SKYBLUE (3125 -150);
FORCEPROP 1 LASTPIN (3075 -200) $PN 2
J 0
(3085 -220);
DISPLAY 0.787234 (3085 -220);
PAINT ORANGE (3085 -220);
FORCEPROP 1 LAST MATERIAL X7R
J 0
(3125 -200);
DISPLAY 0.617021 (3125 -200);
PAINT SKYBLUE (3125 -200);
FORCEPROP 1 LAST PART_NUMBER A36096-046
J 0
(3125 -250);
DISPLAY 0.617021 (3125 -250);
PAINT BLUE (3125 -250);
FORCEPROP 1 LAST PACK_TYPE 0402LF
J 0
(3125 -300);
DISPLAY 0.617021 (3125 -300);
PAINT SKYBLUE (3125 -300);
FORCEPROP 0 LAST BOM_SS NOPOP
J 0
(3125 -325);
DISPLAY 0.638298 (3125 -325);
PAINT BROWN (3125 -325);
DISPLAY BOTH (3125 -325);
FORCEPROP 1 LAST LOCATION CT48
J 0
(2975 -50);
DISPLAY 0.617021 (2975 -50);
PAINT AQUA (2975 -50);
FORCEPROP 2 LAST SEC_TYPE 0402LF
J 0
(3125 100);
DISPLAY 1.021277 (3125 100);
PAINT ORANGE (3125 100);
DISPLAY INVISIBLE (3125 100);
FORCEPROP 0 LAST SEC 1
J 0
(3125 50);
DISPLAY 0.680851 (3125 50);
PAINT MONO (3125 50);
DISPLAY INVISIBLE (3125 50);
FORCEPROP 2 LAST CDS_LIB mstr_discrete
J 0
(3075 -100);
PAINT MONO (3075 -100);
DISPLAY INVISIBLE (3075 -100);
FORCEPROP 1 LAST PATH I119
J 0
(3125 50);
DISPLAY 0.978723 (3125 50);
PAINT WHITE (3125 50);
DISPLAY INVISIBLE (3125 50);
FORCEPROP 0 LAST ROOM VDDQ_KLM_PWR_VR
J 0
(3125 100);
DISPLAY 1.021277 (3125 100);
PAINT ORANGE (3125 100);
DISPLAY INVISIBLE (3125 100);
FORCEADD GND..1
(3075 -300);
FORCEPROP 3 LASTPIN (3075 -250) SIG_NAME GND\g
J 0
(3085 -240);
DISPLAY 0.659574 (3085 -240);
PAINT MONO (3085 -240);
DISPLAY INVISIBLE (3085 -240);
FORCEPROP 2 LAST CDS_LIB mstr_symbols
J 0
(3075 -300);
PAINT MONO (3075 -300);
DISPLAY INVISIBLE (3075 -300);
FORCEPROP 1 LAST PATH I120
J 0
(3150 -300);
DISPLAY 0.872340 (3150 -300);
PAINT AQUA (3150 -300);
DISPLAY INVISIBLE (3150 -300);
FORCEPROP 1 LAST SIZE 1B
J 0
(3150 -350);
DISPLAY 1.170213 (3150 -350);
PAINT AQUA (3150 -350);
DISPLAY INVISIBLE (3150 -350);
FORCEPROP 1 LAST VOLTAGE 0
J 0
(3075 -300);
PAINT SKYBLUE (3075 -300);
DISPLAY INVISIBLE (3075 -300);
FORCEPROP 2 LAST ROOM VDDQ_KLM_PWR_VR
J 0
(2500 -225);
DISPLAY 1.361702 (2500 -225);
PAINT ORANGE (2500 -225);
DISPLAY INVISIBLE (2500 -225);
FORCEPROP 1 LAST BODY_TYPE PLUMBING
J 0
(3030 -343);
DISPLAY 0.340426 (3030 -343);
PAINT GREEN (3030 -343);
DISPLAY INVISIBLE (3030 -343);
FORCEPROP 1 LAST HDL_POWER GND
J 0
(3075 -150);
DISPLAY 1.170213 (3075 -150);
PAINT GREEN (3075 -150);
DISPLAY INVISIBLE (3075 -150);
FORCEADD GND..1
(2875 -1125);
FORCEPROP 3 LASTPIN (2875 -1075) SIG_NAME GND\g
J 0
(2885 -1065);
DISPLAY 0.659574 (2885 -1065);
PAINT MONO (2885 -1065);
DISPLAY INVISIBLE (2885 -1065);
FORCEPROP 2 LAST CDS_LIB mstr_symbols
J 0
(2875 -1125);
PAINT MONO (2875 -1125);
DISPLAY INVISIBLE (2875 -1125);
FORCEPROP 1 LAST PATH I122
J 0
(2950 -1125);
DISPLAY 0.872340 (2950 -1125);
PAINT AQUA (2950 -1125);
DISPLAY INVISIBLE (2950 -1125);
FORCEPROP 2 LAST ROOM PVCCIN_CPU0_PWR_VR
J 0
(2325 -1050);
DISPLAY 1.936170 (2325 -1050);
PAINT ORANGE (2325 -1050);
DISPLAY INVISIBLE (2325 -1050);
FORCEPROP 2 LAST BOM_COST PROC_VRD_VCCIN_CPU0
J 0
(2500 -1050);
DISPLAY 1.446809 (2500 -1050);
PAINT MONO (2500 -1050);
DISPLAY INVISIBLE (2500 -1050);
FORCEPROP 1 LAST VOLTAGE 0
J 0
(2875 -1125);
PAINT SKYBLUE (2875 -1125);
DISPLAY INVISIBLE (2875 -1125);
FORCEPROP 1 LAST SIZE 1B
J 0
(2950 -1175);
DISPLAY 1.723404 (2950 -1175);
PAINT GREEN (2950 -1175);
DISPLAY INVISIBLE (2950 -1175);
FORCEPROP 1 LAST BODY_TYPE PLUMBING
J 0
(2830 -1168);
DISPLAY 0.340426 (2830 -1168);
PAINT GREEN (2830 -1168);
DISPLAY INVISIBLE (2830 -1168);
FORCEPROP 1 LAST HDL_POWER GND
J 0
(2875 -975);
DISPLAY 1.723404 (2875 -975);
PAINT GREEN (2875 -975);
DISPLAY INVISIBLE (2875 -975);
FORCEADD CAP..1
(2900 2125);
FORCEPROP 1 LASTPIN (2900 2025) $PN 2
J 0
(2910 2005);
DISPLAY 0.787234 (2910 2005);
PAINT ORANGE (2910 2005);
FORCEPROP 1 LAST PART_NUMBER A36096-046
J 0
(2950 1975);
DISPLAY 0.617021 (2950 1975);
PAINT BLUE (2950 1975);
FORCEPROP 1 LAST MATERIAL X7R
J 0
(2950 2025);
DISPLAY 0.617021 (2950 2025);
PAINT SKYBLUE (2950 2025);
FORCEPROP 1 LAST TOLERANCE 10%
J 0
(2950 2075);
DISPLAY 0.617021 (2950 2075);
PAINT SKYBLUE (2950 2075);
FORCEPROP 1 LAST VOLTAGE 50V
J 0
(2950 2125);
DISPLAY 0.617021 (2950 2125);
PAINT SKYBLUE (2950 2125);
FORCEPROP 1 LAST LOCATION CT43
J 0
(2750 2125);
DISPLAY 0.617021 (2750 2125);
PAINT AQUA (2750 2125);
FORCEPROP 1 LASTPIN (2900 2225) $PN 1
J 0
(2910 2205);
DISPLAY 0.787234 (2910 2205);
PAINT ORANGE (2910 2205);
FORCEPROP 1 LAST VALUE 1000PF
J 0
(2950 2175);
DISPLAY 0.617021 (2950 2175);
PAINT SKYBLUE (2950 2175);
FORCEPROP 1 LAST PACK_TYPE 0402LF
J 0
(2950 1925);
DISPLAY 0.617021 (2950 1925);
PAINT SKYBLUE (2950 1925);
FORCEPROP 0 LAST POP NOPOP
J 0
(2650 2000);
DISPLAY 1.021277 (2650 2000);
PAINT ORANGE (2650 2000);
FORCEPROP 0 LAST ROOM VDDQ_KLM_PWR_VR
J 0
(2950 2325);
DISPLAY 1.021277 (2950 2325);
PAINT ORANGE (2950 2325);
DISPLAY INVISIBLE (2950 2325);
FORCEPROP 1 LAST PATH I124
J 0
(2950 2275);
DISPLAY 0.978723 (2950 2275);
PAINT WHITE (2950 2275);
DISPLAY INVISIBLE (2950 2275);
FORCEPROP 2 LAST CDS_LIB mstr_discrete
J 0
(2900 2125);
PAINT MONO (2900 2125);
DISPLAY INVISIBLE (2900 2125);
FORCEPROP 0 LAST SEC 1
J 0
(2950 2225);
DISPLAY 0.680851 (2950 2225);
PAINT MONO (2950 2225);
DISPLAY INVISIBLE (2950 2225);
FORCEPROP 2 LAST SEC_TYPE 0402LF
J 0
(2950 2325);
DISPLAY 1.021277 (2950 2325);
PAINT ORANGE (2950 2325);
DISPLAY INVISIBLE (2950 2325);
FORCEADD GND..1
(2900 1925);
FORCEPROP 3 LASTPIN (2900 1975) SIG_NAME GND\g
J 0
(2910 1985);
DISPLAY 0.659574 (2910 1985);
PAINT MONO (2910 1985);
DISPLAY INVISIBLE (2910 1985);
FORCEPROP 1 LAST HDL_POWER GND
J 0
(2900 2075);
DISPLAY 1.170213 (2900 2075);
PAINT GREEN (2900 2075);
DISPLAY INVISIBLE (2900 2075);
FORCEPROP 1 LAST BODY_TYPE PLUMBING
J 0
(2855 1882);
DISPLAY 0.340426 (2855 1882);
PAINT GREEN (2855 1882);
DISPLAY INVISIBLE (2855 1882);
FORCEPROP 1 LAST SIZE 1B
J 0
(2975 1875);
DISPLAY 1.170213 (2975 1875);
PAINT AQUA (2975 1875);
DISPLAY INVISIBLE (2975 1875);
FORCEPROP 1 LAST VOLTAGE 0
J 0
(2900 1925);
PAINT SKYBLUE (2900 1925);
DISPLAY INVISIBLE (2900 1925);
FORCEPROP 2 LAST ROOM VDDQ_KLM_PWR_VR
J 0
(2325 2000);
DISPLAY 1.361702 (2325 2000);
PAINT ORANGE (2325 2000);
DISPLAY INVISIBLE (2325 2000);
FORCEPROP 1 LAST PATH I125
J 0
(2975 1925);
DISPLAY 0.872340 (2975 1925);
PAINT AQUA (2975 1925);
DISPLAY INVISIBLE (2975 1925);
FORCEPROP 2 LAST CDS_LIB mstr_symbols
J 0
(2900 1925);
PAINT MONO (2900 1925);
DISPLAY INVISIBLE (2900 1925);
FORCEADD GND..1
(2850 1150);
FORCEPROP 3 LASTPIN (2850 1200) SIG_NAME GND\g
J 0
(2860 1210);
DISPLAY 0.659574 (2860 1210);
PAINT MONO (2860 1210);
DISPLAY INVISIBLE (2860 1210);
FORCEPROP 2 LAST CDS_LIB mstr_symbols
J 0
(2850 1150);
PAINT MONO (2850 1150);
DISPLAY INVISIBLE (2850 1150);
FORCEPROP 1 LAST PATH I128
J 0
(2925 1150);
DISPLAY 0.872340 (2925 1150);
PAINT AQUA (2925 1150);
DISPLAY INVISIBLE (2925 1150);
FORCEPROP 2 LAST ROOM PVCCIN_CPU0_PWR_VR
J 0
(2300 1225);
DISPLAY 1.936170 (2300 1225);
PAINT ORANGE (2300 1225);
DISPLAY INVISIBLE (2300 1225);
FORCEPROP 2 LAST BOM_COST PROC_VRD_VCCIN_CPU0
J 0
(2475 1225);
DISPLAY 1.446809 (2475 1225);
PAINT MONO (2475 1225);
DISPLAY INVISIBLE (2475 1225);
FORCEPROP 1 LAST VOLTAGE 0
J 0
(2850 1150);
PAINT SKYBLUE (2850 1150);
DISPLAY INVISIBLE (2850 1150);
FORCEPROP 1 LAST SIZE 1B
J 0
(2925 1100);
DISPLAY 1.723404 (2925 1100);
PAINT GREEN (2925 1100);
DISPLAY INVISIBLE (2925 1100);
FORCEPROP 1 LAST BODY_TYPE PLUMBING
J 0
(2805 1107);
DISPLAY 0.340426 (2805 1107);
PAINT GREEN (2805 1107);
DISPLAY INVISIBLE (2805 1107);
FORCEPROP 1 LAST HDL_POWER GND
J 0
(2850 1300);
DISPLAY 1.723404 (2850 1300);
PAINT GREEN (2850 1300);
DISPLAY INVISIBLE (2850 1300);
FORCEADD CAP..1
(2850 1625);
FORCEPROP 1 LASTPIN (2850 1525) $PN 2
J 0
(2860 1505);
DISPLAY 0.787234 (2860 1505);
PAINT ORANGE (2860 1505);
FORCEPROP 1 LASTPIN (2850 1725) $PN 1
J 0
(2860 1705);
DISPLAY 0.787234 (2860 1705);
PAINT ORANGE (2860 1705);
FORCEPROP 1 LAST LOCATION CT44
J 0
(2900 1675);
DISPLAY 0.617021 (2900 1675);
PAINT AQUA (2900 1675);
FORCEPROP 1 LAST TOLERANCE 10%
J 0
(2900 1625);
DISPLAY 0.617021 (2900 1625);
PAINT SKYBLUE (2900 1625);
FORCEPROP 1 LAST MATERIAL X7R
J 0
(3000 1625);
DISPLAY 0.617021 (3000 1625);
PAINT SKYBLUE (3000 1625);
FORCEPROP 1 LAST VOLTAGE 50V
J 0
(3200 1675);
DISPLAY 0.617021 (3200 1675);
PAINT SKYBLUE (3200 1675);
FORCEPROP 1 LAST VALUE 1000PF
J 0
(3025 1675);
DISPLAY 0.617021 (3025 1675);
PAINT SKYBLUE (3025 1675);
FORCEPROP 1 LAST PACK_TYPE 0402LF
J 0
(3100 1625);
DISPLAY 0.617021 (3100 1625);
PAINT SKYBLUE (3100 1625);
FORCEPROP 1 LAST PART_NUMBER A36096-046
J 0
(2925 1575);
DISPLAY 0.617021 (2925 1575);
PAINT BLUE (2925 1575);
FORCEPROP 0 LAST POP NOPOP
J 0
(3175 1575);
DISPLAY 0.808511 (3175 1575);
PAINT RED (3175 1575);
FORCEPROP 2 LAST SEC_TYPE 0402LF
J 0
(2900 1825);
DISPLAY 1.021277 (2900 1825);
PAINT ORANGE (2900 1825);
DISPLAY INVISIBLE (2900 1825);
FORCEPROP 0 LAST SEC 1
J 0
(2900 1775);
DISPLAY 0.680851 (2900 1775);
PAINT MONO (2900 1775);
DISPLAY INVISIBLE (2900 1775);
FORCEPROP 2 LAST CDS_LIB mstr_discrete
J 0
(2850 1625);
PAINT MONO (2850 1625);
DISPLAY INVISIBLE (2850 1625);
FORCEPROP 1 LAST PATH I137
J 0
(2900 1775);
DISPLAY 0.978723 (2900 1775);
PAINT WHITE (2900 1775);
DISPLAY INVISIBLE (2900 1775);
FORCEPROP 0 LAST ROOM VDDQ_KLM_PWR_VR
J 0
(2900 1825);
DISPLAY 1.021277 (2900 1825);
PAINT ORANGE (2900 1825);
DISPLAY INVISIBLE (2900 1825);
FORCEADD CAP..1
(2875 -600);
FORCEPROP 1 LAST PART_NUMBER A36096-046
J 0
(3125 -600);
DISPLAY 0.617021 (3125 -600);
PAINT BLUE (3125 -600);
FORCEPROP 0 LAST POP NOPOP
J 0
(3125 -650);
DISPLAY 0.808511 (3125 -650);
PAINT RED (3125 -650);
FORCEPROP 1 LASTPIN (2875 -700) $PN 2
J 0
(2885 -720);
DISPLAY 0.787234 (2885 -720);
PAINT ORANGE (2885 -720);
FORCEPROP 1 LASTPIN (2875 -500) $PN 1
J 0
(2885 -520);
DISPLAY 0.787234 (2885 -520);
PAINT ORANGE (2885 -520);
FORCEPROP 1 LAST VOLTAGE 50V
J 0
(3225 -550);
DISPLAY 0.617021 (3225 -550);
PAINT SKYBLUE (3225 -550);
FORCEPROP 1 LAST VALUE 1000PF
J 0
(3050 -550);
DISPLAY 0.617021 (3050 -550);
PAINT SKYBLUE (3050 -550);
FORCEPROP 1 LAST MATERIAL X7R
J 0
(3025 -600);
DISPLAY 0.617021 (3025 -600);
PAINT SKYBLUE (3025 -600);
FORCEPROP 1 LAST LOCATION CT47
J 0
(2925 -550);
DISPLAY 0.617021 (2925 -550);
PAINT AQUA (2925 -550);
FORCEPROP 0 LAST BOM_SS NOPOP
J 0
(3100 -700);
DISPLAY 0.638298 (3100 -700);
PAINT BROWN (3100 -700);
DISPLAY BOTH (3100 -700);
FORCEPROP 1 LAST PACK_TYPE 0402LF
J 0
(2950 -650);
DISPLAY 0.617021 (2950 -650);
PAINT SKYBLUE (2950 -650);
FORCEPROP 1 LAST TOLERANCE 10%
J 0
(2925 -600);
DISPLAY 0.617021 (2925 -600);
PAINT SKYBLUE (2925 -600);
FORCEPROP 2 LAST CDS_LIB mstr_discrete
J 0
(2875 -600);
PAINT MONO (2875 -600);
DISPLAY INVISIBLE (2875 -600);
FORCEPROP 1 LAST PATH I138
J 0
(2925 -450);
DISPLAY 0.978723 (2925 -450);
PAINT WHITE (2925 -450);
DISPLAY INVISIBLE (2925 -450);
FORCEPROP 0 LAST ROOM VDDQ_KLM_PWR_VR
J 0
(2925 -400);
DISPLAY 1.021277 (2925 -400);
PAINT ORANGE (2925 -400);
DISPLAY INVISIBLE (2925 -400);
FORCEPROP 0 LAST SEC 1
J 0
(2925 -450);
DISPLAY 0.680851 (2925 -450);
PAINT MONO (2925 -450);
DISPLAY INVISIBLE (2925 -450);
FORCEPROP 2 LAST SEC_TYPE 0402LF
J 0
(2925 -400);
DISPLAY 1.021277 (2925 -400);
PAINT ORANGE (2925 -400);
DISPLAY INVISIBLE (2925 -400);
FORCEADD RES..1
(-125 1900);
FORCEPROP 1 LAST WATTAGE 1/10W
J 2
(-150 1750);
DISPLAY 0.617021 (-150 1750);
PAINT SKYBLUE (-150 1750);
FORCEPROP 1 LASTPIN (-25 1900) $PN 2
J 0
(-63 1912);
DISPLAY 0.787234 (-63 1912);
PAINT ORANGE (-63 1912);
FORCEPROP 1 LAST VALUE 0
J 2
(-175 1850);
DISPLAY 0.617021 (-175 1850);
PAINT SKYBLUE (-175 1850);
FORCEPROP 1 LASTPIN (-225 1900) $PN 1
J 0
(-213 1912);
DISPLAY 0.787234 (-213 1912);
PAINT ORANGE (-213 1912);
FORCEPROP 1 LAST TOLERANCE 5.0%
J 0
(-125 1800);
DISPLAY 0.617021 (-125 1800);
PAINT SKYBLUE (-125 1800);
FORCEPROP 1 LAST PACK_TYPE 0603
J 0
(-50 1850);
DISPLAY 0.617021 (-50 1850);
PAINT SKYBLUE (-50 1850);
FORCEPROP 1 LAST LOCATION RT30
J 0
(-25 1925);
DISPLAY 0.617021 (-25 1925);
PAINT AQUA (-25 1925);
FORCEPROP 1 LAST MATERIAL CHIP
J 0
(-125 1750);
DISPLAY 0.617021 (-125 1750);
PAINT SKYBLUE (-125 1750);
FORCEPROP 1 LAST PART_NUMBER G22178-002
J 0
(-375 1950);
DISPLAY 0.617021 (-375 1950);
PAINT BLUE (-375 1950);
FORCEPROP 0 LAST ROOM NIC_SPRV
J 0
(-25 2025);
DISPLAY 1.021277 (-25 2025);
PAINT ORANGE (-25 2025);
DISPLAY INVISIBLE (-25 2025);
FORCEPROP 0 LAST BOM_COST NT_GBE_BASE
J 0
(-25 2125);
DISPLAY 1.021277 (-25 2125);
PAINT ORANGE (-25 2125);
DISPLAY INVISIBLE (-25 2125);
FORCEPROP 1 LAST PATH I141
J 0
(-175 2050);
DISPLAY 0.978723 (-175 2050);
PAINT WHITE (-175 2050);
DISPLAY INVISIBLE (-175 2050);
FORCEPROP 2 LAST CDS_LIB mstr_discrete
J 0
(-125 1900);
PAINT MONO (-125 1900);
DISPLAY INVISIBLE (-125 1900);
FORCEPROP 0 LAST SEC 1
J 0
(-375 2000);
DISPLAY 0.680851 (-375 2000);
PAINT MONO (-375 2000);
DISPLAY INVISIBLE (-375 2000);
FORCEPROP 2 LAST SEC_TYPE 0603
J 0
(-175 2100);
DISPLAY 1.021277 (-175 2100);
PAINT ORANGE (-175 2100);
DISPLAY INVISIBLE (-175 2100);
FORCEADD RES..1
(175 -350);
FORCEPROP 0 LAST BOM_SS NOPOP
J 0
(425 -600);
DISPLAY 0.638298 (425 -600);
PAINT BROWN (425 -600);
DISPLAY BOTH (425 -600);
FORCEPROP 1 LAST PART_NUMBER G22178-002
J 0
(75 -575);
DISPLAY 0.617021 (75 -575);
PAINT BLUE (75 -575);
FORCEPROP 1 LAST TOLERANCE 5.0%
J 0
(425 -475);
DISPLAY 0.617021 (425 -475);
PAINT SKYBLUE (425 -475);
FORCEPROP 1 LAST LOCATION RT31
J 0
(100 -425);
DISPLAY 0.617021 (100 -425);
PAINT AQUA (100 -425);
FORCEPROP 1 LAST WATTAGE 1/10W
J 2
(525 -425);
DISPLAY 0.617021 (525 -425);
PAINT SKYBLUE (525 -425);
FORCEPROP 1 LAST VALUE 0
J 2
(125 -475);
DISPLAY 0.617021 (125 -475);
PAINT SKYBLUE (125 -475);
FORCEPROP 1 LAST PACK_TYPE 0603
J 0
(100 -525);
DISPLAY 0.617021 (100 -525);
PAINT SKYBLUE (100 -525);
FORCEPROP 1 LAST MATERIAL CHIP
J 0
(425 -525);
DISPLAY 0.617021 (425 -525);
PAINT SKYBLUE (425 -525);
FORCEPROP 1 LASTPIN (275 -350) $PN 2
J 0
(237 -338);
DISPLAY 0.787234 (237 -338);
PAINT ORANGE (237 -338);
FORCEPROP 1 LASTPIN (75 -350) $PN 1
J 0
(87 -338);
DISPLAY 0.787234 (87 -338);
PAINT ORANGE (87 -338);
FORCEPROP 0 LAST SEC 1
J 0
(-75 -250);
DISPLAY 0.680851 (-75 -250);
PAINT MONO (-75 -250);
DISPLAY INVISIBLE (-75 -250);
FORCEPROP 2 LAST SEC_TYPE 0603
J 0
(125 -150);
DISPLAY 1.021277 (125 -150);
PAINT ORANGE (125 -150);
DISPLAY INVISIBLE (125 -150);
FORCEPROP 2 LAST CDS_LIB mstr_discrete
J 0
(175 -350);
PAINT MONO (175 -350);
DISPLAY INVISIBLE (175 -350);
FORCEPROP 1 LAST PATH I142
J 0
(125 -200);
DISPLAY 0.978723 (125 -200);
PAINT WHITE (125 -200);
DISPLAY INVISIBLE (125 -200);
FORCEPROP 0 LAST BOM_COST NT_GBE_BASE
J 0
(275 -125);
DISPLAY 1.021277 (275 -125);
PAINT ORANGE (275 -125);
DISPLAY INVISIBLE (275 -125);
FORCEPROP 0 LAST ROOM NIC_SPRV
J 0
(275 -225);
DISPLAY 1.021277 (275 -225);
PAINT ORANGE (275 -225);
DISPLAY INVISIBLE (275 -225);
FORCEADD RES..1
(-725 3000);
FORCEPROP 1 LAST LOCATION R3L6
J 0
(-825 3050);
DISPLAY 0.617021 (-825 3050);
PAINT AQUA (-825 3050);
FORCEPROP 1 LASTPIN (-825 3000) $PN 1
J 0
(-813 3012);
DISPLAY 0.617021 (-813 3012);
PAINT WHITE (-813 3012);
FORCEPROP 1 LAST PACK_TYPE 0402
J 0
(-650 2900);
DISPLAY 0.617021 (-650 2900);
PAINT SKYBLUE (-650 2900);
FORCEPROP 1 LASTPIN (-625 3000) $PN 2
J 0
(-663 3012);
DISPLAY 0.617021 (-663 3012);
PAINT WHITE (-663 3012);
FORCEPROP 1 LAST TOLERANCE 5%
J 0
(-775 2900);
DISPLAY 0.617021 (-775 2900);
PAINT SKYBLUE (-775 2900);
FORCEPROP 1 LAST MATERIAL CHIP
J 0
(-475 2900);
DISPLAY 0.510638 (-475 2900);
PAINT SKYBLUE (-475 2900);
FORCEPROP 1 LAST WATTAGE 1/16W
J 2
(-350 3025);
DISPLAY 0.510638 (-350 3025);
PAINT SKYBLUE (-350 3025);
FORCEPROP 1 LAST PART_NUMBER G21497-005
J 0
(-850 2950);
DISPLAY 0.617021 (-850 2950);
PAINT BLUE (-850 2950);
FORCEPROP 1 LAST VALUE 0.0
J 2
(-825 2900);
DISPLAY 0.617021 (-825 2900);
PAINT SKYBLUE (-825 2900);
FORCEPROP 2 LAST CDS_LOCATION R3L6
J 0
(-1200 3000);
DISPLAY 0.617021 (-1200 3000);
PAINT AQUA (-1200 3000);
DISPLAY INVISIBLE (-1200 3000);
FORCEPROP 1 LAST PATH I147
J 0
(-775 3150);
DISPLAY 0.978723 (-775 3150);
PAINT WHITE (-775 3150);
DISPLAY INVISIBLE (-775 3150);
FORCEPROP 0 LAST CDS_SEC 1
J 0
(-425 3050);
PAINT MONO (-425 3050);
DISPLAY INVISIBLE (-425 3050);
FORCEPROP 2 LAST ROOM CPU0
J 0
(-775 3150);
PAINT PEACH (-775 3150);
DISPLAY INVISIBLE (-775 3150);
FORCEPROP 2 LAST SEC 1
J 0
(-775 3225);
DISPLAY 0.680851 (-775 3225);
PAINT MONO (-775 3225);
DISPLAY INVISIBLE (-775 3225);
FORCEPROP 2 LAST SEC_TYPE 0402
J 0
(-775 3225);
DISPLAY 1.021277 (-775 3225);
PAINT ORANGE (-775 3225);
DISPLAY INVISIBLE (-775 3225);
FORCEPROP 2 LAST CDS_LIB mstr_discrete
J 0
(-725 3000);
DISPLAY 1.340426 (-725 3000);
PAINT ORANGE (-725 3000);
DISPLAY INVISIBLE (-725 3000);
FORCEPROP 2 LAST BOM_COST PROC_SIDEBAND
J 0
(-725 3000);
PAINT MONO (-725 3000);
DISPLAY INVISIBLE (-725 3000);
FORCEADD RES..1
(-775 700);
FORCEPROP 1 LAST WATTAGE 1/16W
J 2
(-400 725);
DISPLAY 0.510638 (-400 725);
PAINT SKYBLUE (-400 725);
FORCEPROP 1 LASTPIN (-675 700) $PN 2
J 0
(-713 712);
DISPLAY 0.617021 (-713 712);
PAINT WHITE (-713 712);
FORCEPROP 1 LASTPIN (-875 700) $PN 1
J 0
(-863 712);
DISPLAY 0.617021 (-863 712);
PAINT WHITE (-863 712);
FORCEPROP 0 LAST BOM_SS NOPOP
J 0
(-525 750);
DISPLAY 0.638298 (-525 750);
PAINT BROWN (-525 750);
DISPLAY BOTH (-525 750);
FORCEPROP 1 LAST LOCATION R3L8
J 0
(-875 750);
DISPLAY 0.617021 (-875 750);
PAINT AQUA (-875 750);
FORCEPROP 1 LAST VALUE 0.0
J 2
(-875 600);
DISPLAY 0.617021 (-875 600);
PAINT SKYBLUE (-875 600);
FORCEPROP 1 LAST TOLERANCE 5%
J 0
(-825 600);
DISPLAY 0.617021 (-825 600);
PAINT SKYBLUE (-825 600);
FORCEPROP 1 LAST PART_NUMBER G21497-005
J 0
(-900 650);
DISPLAY 0.617021 (-900 650);
PAINT BLUE (-900 650);
FORCEPROP 1 LAST PACK_TYPE 0402
J 0
(-700 600);
DISPLAY 0.617021 (-700 600);
PAINT SKYBLUE (-700 600);
FORCEPROP 1 LAST MATERIAL CHIP
J 0
(-500 600);
DISPLAY 0.510638 (-500 600);
PAINT SKYBLUE (-500 600);
FORCEPROP 2 LAST CDS_LOCATION R3L8
J 0
(-1250 700);
DISPLAY 0.617021 (-1250 700);
PAINT AQUA (-1250 700);
DISPLAY INVISIBLE (-1250 700);
FORCEPROP 1 LAST PATH I148
J 0
(-825 850);
DISPLAY 0.978723 (-825 850);
PAINT WHITE (-825 850);
DISPLAY INVISIBLE (-825 850);
FORCEPROP 2 LAST BOM_COST PROC_SIDEBAND
J 0
(-775 700);
PAINT MONO (-775 700);
DISPLAY INVISIBLE (-775 700);
FORCEPROP 2 LAST CDS_LIB mstr_discrete
J 0
(-775 700);
DISPLAY 1.340426 (-775 700);
PAINT ORANGE (-775 700);
DISPLAY INVISIBLE (-775 700);
FORCEPROP 2 LAST SEC_TYPE 0402
J 0
(-825 925);
DISPLAY 1.021277 (-825 925);
PAINT ORANGE (-825 925);
DISPLAY INVISIBLE (-825 925);
FORCEPROP 2 LAST SEC 1
J 0
(-825 925);
DISPLAY 0.680851 (-825 925);
PAINT MONO (-825 925);
DISPLAY INVISIBLE (-825 925);
FORCEPROP 2 LAST ROOM CPU0
J 0
(-825 850);
PAINT PEACH (-825 850);
DISPLAY INVISIBLE (-825 850);
FORCEPROP 0 LAST CDS_SEC 1
J 0
(-475 750);
PAINT MONO (-475 750);
DISPLAY INVISIBLE (-475 750);
FORCEADD SC1U10V2KX-4-GP..1
(-450 2350);
FORCEPROP 1 LAST VALUE SC1U10V2KX-4-GP
R 1
J 0
(-350 2150);
DISPLAY 0.617021 (-350 2150);
PAINT GREEN (-350 2150);
FORCEPROP 2 LASTPIN (-450 2275) $PN 2
R 1
J 2
(-460 2265);
DISPLAY 0.808511 (-460 2265);
PAINT ORANGE (-460 2265);
FORCEPROP 1 LAST LOCATION C7A18
J 0
(-325 2430);
DISPLAY 0.617021 (-325 2430);
PAINT GREEN (-325 2430);
FORCEPROP 2 LAST TOLERANCE 10%
J 0
(-325 2325);
DISPLAY 0.638298 (-325 2325);
PAINT GREEN (-325 2325);
FORCEPROP 2 LAST RATED 10V
J 0
(-325 2275);
DISPLAY 0.638298 (-325 2275);
PAINT GREEN (-325 2275);
FORCEPROP 2 LAST PACK_SIZE 0402
J 0
(-325 2225);
DISPLAY 0.638298 (-325 2225);
PAINT GREEN (-325 2225);
FORCEPROP 2 LAST ATTRIBUTE 1UF
J 0
(-325 2375);
DISPLAY 0.638298 (-325 2375);
PAINT GREEN (-325 2375);
FORCEPROP 2 LASTPIN (-450 2425) $PN 1
R 1
J 0
(-460 2435);
DISPLAY 0.808511 (-460 2435);
PAINT ORANGE (-460 2435);
FORCEPROP 1 LAST PART_NUMBER 78.10523.8FL
J 0
(-450 2350);
DISPLAY 0.617021 (-450 2350);
PAINT GREEN (-450 2350);
DISPLAY INVISIBLE (-450 2350);
FORCEPROP 2 LAST CDS_LIB w_hdl
J 0
(-450 2350);
PAINT MONO (-450 2350);
DISPLAY INVISIBLE (-450 2350);
FORCEPROP 1 LAST PATH I151
J 0
(-450 2350);
DISPLAY 0.617021 (-450 2350);
PAINT GREEN (-450 2350);
DISPLAY INVISIBLE (-450 2350);
FORCEPROP 1 LAST CDS_LMAN_SYM_OUTLINE -50,25,50,-25
J 0
(-450 2350);
DISPLAY 0.468085 (-450 2350);
PAINT GREEN (-450 2350);
DISPLAY INVISIBLE (-450 2350);
FORCEPROP 2 LAST SEC_TYPE SMD-BCG6
J 0
(-425 2425);
DISPLAY 1.021277 (-425 2425);
PAINT ORANGE (-425 2425);
DISPLAY INVISIBLE (-425 2425);
FORCEPROP 2 LAST SEC 1
J 0
(-425 2425);
DISPLAY 0.680851 (-425 2425);
PAINT MONO (-425 2425);
DISPLAY INVISIBLE (-425 2425);
FORCEPROP 1 LAST PACK_TYPE SMD-BCG6
J 0
(-450 2350);
DISPLAY 0.617021 (-450 2350);
PAINT GREEN (-450 2350);
DISPLAY INVISIBLE (-450 2350);
FORCEADD SC1U10V2KX-4-GP..1
(-525 100);
FORCEPROP 0 LAST BOM_SS NOPOP
J 0
(-400 -75);
DISPLAY 0.638298 (-400 -75);
PAINT BROWN (-400 -75);
DISPLAY BOTH (-400 -75);
FORCEPROP 2 LASTPIN (-525 25) $PN 2
R 1
J 2
(-535 15);
DISPLAY 0.808511 (-535 15);
PAINT ORANGE (-535 15);
FORCEPROP 2 LASTPIN (-525 175) $PN 1
R 1
J 0
(-535 185);
DISPLAY 0.808511 (-535 185);
PAINT ORANGE (-535 185);
FORCEPROP 2 LAST ATTRIBUTE 1UF
J 0
(-400 125);
DISPLAY 0.638298 (-400 125);
PAINT GREEN (-400 125);
FORCEPROP 2 LAST TOLERANCE 10%
J 0
(-400 75);
DISPLAY 0.638298 (-400 75);
PAINT GREEN (-400 75);
FORCEPROP 2 LAST RATED 10V
J 0
(-400 25);
DISPLAY 0.638298 (-400 25);
PAINT GREEN (-400 25);
FORCEPROP 2 LAST PACK_SIZE 0402
J 0
(-400 -25);
DISPLAY 0.638298 (-400 -25);
PAINT GREEN (-400 -25);
FORCEPROP 1 LAST LOCATION C7A26
J 0
(-400 180);
DISPLAY 0.617021 (-400 180);
PAINT GREEN (-400 180);
FORCEPROP 1 LAST VALUE SC1U10V2KX-4-GP
R 1
J 0
(-425 -125);
DISPLAY 0.617021 (-425 -125);
PAINT GREEN (-425 -125);
FORCEPROP 1 LAST PART_NUMBER 78.10523.8FL
J 0
(-525 100);
DISPLAY 0.617021 (-525 100);
PAINT GREEN (-525 100);
DISPLAY INVISIBLE (-525 100);
FORCEPROP 2 LAST CDS_LIB w_hdl
J 0
(-525 100);
PAINT MONO (-525 100);
DISPLAY INVISIBLE (-525 100);
FORCEPROP 1 LAST PATH I152
J 0
(-525 100);
DISPLAY 0.617021 (-525 100);
PAINT GREEN (-525 100);
DISPLAY INVISIBLE (-525 100);
FORCEPROP 1 LAST CDS_LMAN_SYM_OUTLINE -50,25,50,-25
J 0
(-525 100);
DISPLAY 0.468085 (-525 100);
PAINT GREEN (-525 100);
DISPLAY INVISIBLE (-525 100);
FORCEPROP 1 LAST PACK_TYPE SMD-BCG6
J 0
(-525 100);
DISPLAY 0.617021 (-525 100);
PAINT GREEN (-525 100);
DISPLAY INVISIBLE (-525 100);
FORCEPROP 2 LAST SEC 1
J 0
(-500 175);
DISPLAY 0.680851 (-500 175);
PAINT MONO (-500 175);
DISPLAY INVISIBLE (-500 175);
FORCEPROP 2 LAST SEC_TYPE SMD-BCG6
J 0
(-500 175);
DISPLAY 1.021277 (-500 175);
PAINT ORANGE (-500 175);
DISPLAY INVISIBLE (-500 175);
FORCEADD 1R3F-GP..1
(2850 1325);
FORCEPROP 2 LASTPIN (2850 1450) $PN 1
R 1
J 0
(2840 1460);
DISPLAY 0.808511 (2840 1460);
PAINT ORANGE (2840 1460);
FORCEPROP 2 LAST TOLERANCE 1%
J 0
(2900 1300);
DISPLAY 0.638298 (2900 1300);
PAINT GREEN (2900 1300);
FORCEPROP 2 LAST ATTRIBUTE 1 OHM
J 0
(2900 1350);
DISPLAY 0.638298 (2900 1350);
PAINT GREEN (2900 1350);
FORCEPROP 2 LAST RATED 1/10W
J 0
(2900 1250);
DISPLAY 0.638298 (2900 1250);
PAINT GREEN (2900 1250);
FORCEPROP 2 LAST PACK_SIZE 0603
J 0
(2900 1200);
DISPLAY 0.638298 (2900 1200);
PAINT GREEN (2900 1200);
FORCEPROP 1 LAST VALUE 1R3F-GP
J 0
(2900 1400);
DISPLAY 0.617021 (2900 1400);
PAINT GREEN (2900 1400);
FORCEPROP 1 LAST LOCATION RT29
J 0
(2900 1450);
DISPLAY 0.617021 (2900 1450);
PAINT GREEN (2900 1450);
FORCEPROP 2 LASTPIN (2850 1200) $PN 2
R 1
J 2
(2840 1190);
DISPLAY 0.808511 (2840 1190);
PAINT ORANGE (2840 1190);
FORCEPROP 0 LAST POP NOPOP
J 0
(2900 1150);
DISPLAY 0.638298 (2900 1150);
PAINT RED (2900 1150);
FORCEPROP 1 LAST PATH I153
J 0
(2850 1325);
DISPLAY 0.617021 (2850 1325);
PAINT GREEN (2850 1325);
DISPLAY INVISIBLE (2850 1325);
FORCEPROP 1 LAST PACK_TYPE RCL_GP
J 0
(2850 1325);
DISPLAY 0.617021 (2850 1325);
PAINT GREEN (2850 1325);
DISPLAY INVISIBLE (2850 1325);
FORCEPROP 2 LAST SEC 1
J 0
(2900 1425);
DISPLAY 0.680851 (2900 1425);
PAINT MONO (2900 1425);
DISPLAY INVISIBLE (2900 1425);
FORCEPROP 2 LAST SEC_TYPE RCL_GP
J 0
(2900 1425);
DISPLAY 1.021277 (2900 1425);
PAINT ORANGE (2900 1425);
DISPLAY INVISIBLE (2900 1425);
FORCEPROP 1 LAST PART_NUMBER 64.1R005.55L
J 0
(2850 1325);
DISPLAY 0.617021 (2850 1325);
PAINT GREEN (2850 1325);
DISPLAY INVISIBLE (2850 1325);
FORCEPROP 2 LAST CDS_LIB w_hdl
J 0
(2850 1325);
DISPLAY INVISIBLE (2850 1325);
FORCEPROP 1 LAST CDS_LMAN_SYM_OUTLINE -50,75,50,-75
J 0
(2850 1325);
DISPLAY 0.468085 (2850 1325);
PAINT GREEN (2850 1325);
DISPLAY INVISIBLE (2850 1325);
FORCEADD 1R3F-GP..1
(2875 -925);
FORCEPROP 0 LAST POP NOPOP
J 0
(2925 -1100);
DISPLAY 0.638298 (2925 -1100);
PAINT RED (2925 -1100);
FORCEPROP 0 LAST BOM_SS NOPOP
J 0
(3100 -925);
DISPLAY 0.638298 (3100 -925);
PAINT BROWN (3100 -925);
DISPLAY BOTH (3100 -925);
FORCEPROP 2 LAST ATTRIBUTE 1 OHM
J 0
(2925 -900);
DISPLAY 0.638298 (2925 -900);
PAINT GREEN (2925 -900);
FORCEPROP 1 LAST VALUE 1R3F-GP
J 0
(2925 -850);
DISPLAY 0.617021 (2925 -850);
PAINT GREEN (2925 -850);
FORCEPROP 2 LASTPIN (2875 -1050) $PN 2
R 1
J 2
(2865 -1060);
DISPLAY 0.808511 (2865 -1060);
PAINT ORANGE (2865 -1060);
FORCEPROP 2 LASTPIN (2875 -800) $PN 1
R 1
J 0
(2865 -790);
DISPLAY 0.808511 (2865 -790);
PAINT ORANGE (2865 -790);
FORCEPROP 2 LAST TOLERANCE 1%
J 0
(2925 -950);
DISPLAY 0.638298 (2925 -950);
PAINT GREEN (2925 -950);
FORCEPROP 1 LAST LOCATION RT32
J 0
(2925 -800);
DISPLAY 0.617021 (2925 -800);
PAINT GREEN (2925 -800);
FORCEPROP 2 LAST RATED 1/10W
J 0
(2925 -1000);
DISPLAY 0.638298 (2925 -1000);
PAINT GREEN (2925 -1000);
FORCEPROP 2 LAST PACK_SIZE 0603
J 0
(2925 -1050);
DISPLAY 0.638298 (2925 -1050);
PAINT GREEN (2925 -1050);
FORCEPROP 1 LAST PACK_TYPE RCL_GP
J 0
(2875 -925);
DISPLAY 0.617021 (2875 -925);
PAINT GREEN (2875 -925);
DISPLAY INVISIBLE (2875 -925);
FORCEPROP 2 LAST SEC 1
J 0
(2925 -825);
DISPLAY 0.680851 (2925 -825);
PAINT MONO (2925 -825);
DISPLAY INVISIBLE (2925 -825);
FORCEPROP 2 LAST SEC_TYPE RCL_GP
J 0
(2925 -825);
DISPLAY 1.021277 (2925 -825);
PAINT ORANGE (2925 -825);
DISPLAY INVISIBLE (2925 -825);
FORCEPROP 1 LAST PART_NUMBER 64.1R005.55L
J 0
(2875 -925);
DISPLAY 0.617021 (2875 -925);
PAINT GREEN (2875 -925);
DISPLAY INVISIBLE (2875 -925);
FORCEPROP 2 LAST CDS_LIB w_hdl
J 0
(2875 -925);
DISPLAY INVISIBLE (2875 -925);
FORCEPROP 1 LAST CDS_LMAN_SYM_OUTLINE -50,75,50,-75
J 0
(2875 -925);
DISPLAY 0.468085 (2875 -925);
PAINT GREEN (2875 -925);
DISPLAY INVISIBLE (2875 -925);
FORCEPROP 1 LAST PATH I154
J 0
(2875 -925);
DISPLAY 0.617021 (2875 -925);
PAINT GREEN (2875 -925);
DISPLAY INVISIBLE (2875 -925);
FORCEADD IND-120NH-30-GP..1
R 1
(3850 1850);
FORCEPROP 0 LAST DS_VALUE 90NH
J 0
(3650 1550);
DISPLAY 0.638298 (3650 1550);
PAINT BROWN (3650 1550);
DISPLAY BOTH (3650 1550);
FORCEPROP 0 LAST SS_ISAT 94A@25C
J 0
(3650 1650);
DISPLAY 0.638298 (3650 1650);
PAINT BROWN (3650 1650);
DISPLAY BOTH (3650 1650);
FORCEPROP 2 LASTPIN (4000 1825) $PN 2
J 0
(4010 1835);
DISPLAY 0.808511 (4010 1835);
PAINT ORANGE (4010 1835);
FORCEPROP 2 LASTPIN (3700 1825) $PN 1
J 2
(3690 1835);
DISPLAY 0.808511 (3690 1835);
PAINT ORANGE (3690 1835);
FORCEPROP 1 LAST LOCATION L7A1
J 0
(3700 1900);
DISPLAY 0.617021 (3700 1900);
PAINT GREEN (3700 1900);
FORCEPROP 0 LAST NEW_PACK_SIZE DCR=0.17MOHM
J 0
(3650 1400);
DISPLAY 0.638298 (3650 1400);
PAINT BROWN (3650 1400);
FORCEPROP 0 LAST BOM_SS 068.1202N.M001
J 0
(3650 1750);
DISPLAY 0.638298 (3650 1750);
PAINT BROWN (3650 1750);
DISPLAY BOTH (3650 1750);
FORCEPROP 0 LAST SS_VALUE 120NH
J 0
(3650 1700);
DISPLAY 0.638298 (3650 1700);
PAINT BROWN (3650 1700);
DISPLAY BOTH (3650 1700);
FORCEPROP 0 LAST BOM_DS 068.9002N.1021
J 0
(3650 1600);
DISPLAY 0.638298 (3650 1600);
PAINT BROWN (3650 1600);
DISPLAY BOTH (3650 1600);
FORCEPROP 0 LAST NEW_TYPE IRMS=66A@DELTA_T<40C
J 0
(3650 1450);
DISPLAY 0.638298 (3650 1450);
PAINT BROWN (3650 1450);
FORCEPROP 0 LAST NEW_RATED DS_ISAT=134A@25C
J 0
(3650 1500);
DISPLAY 0.638298 (3650 1500);
PAINT BROWN (3650 1500);
FORCEPROP 0 LAST TYPE IRMS=66A@DELTA_T<40C
J 0
(3700 1600);
DISPLAY 0.638298 (3700 1600);
PAINT GREEN (3700 1600);
DISPLAY INVISIBLE (3700 1600);
FORCEPROP 0 LAST PACK_SIZE DCR=0.17MOHM
J 0
(3700 1550);
DISPLAY 0.638298 (3700 1550);
PAINT GREEN (3700 1550);
DISPLAY INVISIBLE (3700 1550);
FORCEPROP 0 LAST RATED ISAT=94A@25C
J 0
(3700 1650);
DISPLAY 0.638298 (3700 1650);
PAINT GREEN (3700 1650);
DISPLAY INVISIBLE (3700 1650);
FORCEPROP 0 LAST ATTRIBUTE 120NH
J 0
(3700 1700);
DISPLAY 0.638298 (3700 1700);
PAINT GREEN (3700 1700);
DISPLAY INVISIBLE (3700 1700);
FORCEPROP 1 LAST VALUE IND-120NH-30-GP
J 0
(3700 1750);
DISPLAY 0.617021 (3700 1750);
PAINT GREEN (3700 1750);
DISPLAY INVISIBLE (3700 1750);
FORCEPROP 1 LAST PACK_TYPE DISCRET-GB2
R 1
J 0
(3850 1850);
DISPLAY 0.617021 (3850 1850);
PAINT GREEN (3850 1850);
DISPLAY INVISIBLE (3850 1850);
FORCEPROP 2 LAST SEC 1
J 0
(3725 1925);
DISPLAY 0.680851 (3725 1925);
PAINT MONO (3725 1925);
DISPLAY INVISIBLE (3725 1925);
FORCEPROP 2 LAST SEC_TYPE DISCRET-GB2
J 0
(3725 1925);
DISPLAY 1.021277 (3725 1925);
PAINT ORANGE (3725 1925);
DISPLAY INVISIBLE (3725 1925);
FORCEPROP 1 LAST CDS_LMAN_SYM_OUTLINE -75,100,75,-100
R 1
J 0
(3850 1850);
DISPLAY 0.468085 (3850 1850);
PAINT GREEN (3850 1850);
DISPLAY INVISIBLE (3850 1850);
FORCEPROP 2 LAST CDS_LIB w_hdl
R 1
J 0
(3850 1850);
PAINT MONO (3850 1850);
DISPLAY INVISIBLE (3850 1850);
FORCEPROP 1 LAST PART_NUMBER 068.1202N.M001
R 1
J 0
(3850 1850);
DISPLAY 0.617021 (3850 1850);
PAINT GREEN (3850 1850);
DISPLAY INVISIBLE (3850 1850);
FORCEPROP 1 LAST PATH I157
R 1
J 0
(3850 1850);
DISPLAY 0.617021 (3850 1850);
PAINT GREEN (3850 1850);
DISPLAY INVISIBLE (3850 1850);
FORCEADD IND-120NH-30-GP..1
R 1
(3850 -400);
FORCEPROP 2 LASTPIN (4000 -425) $PN 2
J 0
(4010 -415);
DISPLAY 0.808511 (4010 -415);
PAINT ORANGE (4010 -415);
FORCEPROP 0 LAST BOM_SS NOPOP
J 0
(3650 -500);
DISPLAY 0.638298 (3650 -500);
PAINT BROWN (3650 -500);
DISPLAY BOTH (3650 -500);
FORCEPROP 2 LASTPIN (3700 -425) $PN 1
J 2
(3690 -415);
DISPLAY 0.808511 (3690 -415);
PAINT ORANGE (3690 -415);
FORCEPROP 1 LAST LOCATION L7A3
J 0
(3700 -350);
DISPLAY 0.617021 (3700 -350);
PAINT GREEN (3700 -350);
FORCEPROP 0 LAST DS_VALUE 90NH
J 0
(3650 -600);
DISPLAY 0.638298 (3650 -600);
PAINT BROWN (3650 -600);
DISPLAY BOTH (3650 -600);
FORCEPROP 0 LAST NEW_PACK_SIZE DCR=0.17MOHM
J 0
(3650 -750);
DISPLAY 0.638298 (3650 -750);
PAINT BROWN (3650 -750);
FORCEPROP 0 LAST NEW_RATED DS_ISAT=134A@25C
J 0
(3650 -650);
DISPLAY 0.638298 (3650 -650);
PAINT BROWN (3650 -650);
FORCEPROP 0 LAST BOM_DS 068.9002N.1021
J 0
(3650 -550);
DISPLAY 0.638298 (3650 -550);
PAINT BROWN (3650 -550);
DISPLAY BOTH (3650 -550);
FORCEPROP 0 LAST NEW_TYPE IRMS=66A@DELTA_T<40C
J 0
(3650 -700);
DISPLAY 0.638298 (3650 -700);
PAINT BROWN (3650 -700);
FORCEPROP 1 LAST PART_NUMBER 068.1202N.M001
R 1
J 0
(3850 -400);
DISPLAY 0.617021 (3850 -400);
PAINT GREEN (3850 -400);
DISPLAY INVISIBLE (3850 -400);
FORCEPROP 2 LAST CDS_LIB w_hdl
R 1
J 0
(3850 -400);
PAINT MONO (3850 -400);
DISPLAY INVISIBLE (3850 -400);
FORCEPROP 1 LAST CDS_LMAN_SYM_OUTLINE -75,100,75,-100
R 1
J 0
(3850 -400);
DISPLAY 0.468085 (3850 -400);
PAINT GREEN (3850 -400);
DISPLAY INVISIBLE (3850 -400);
FORCEPROP 2 LAST SEC_TYPE DISCRET-GB2
J 0
(3725 -325);
DISPLAY 1.021277 (3725 -325);
PAINT ORANGE (3725 -325);
DISPLAY INVISIBLE (3725 -325);
FORCEPROP 2 LAST SEC 1
J 0
(3725 -325);
DISPLAY 0.680851 (3725 -325);
PAINT MONO (3725 -325);
DISPLAY INVISIBLE (3725 -325);
FORCEPROP 1 LAST PACK_TYPE DISCRET-GB2
R 1
J 0
(3850 -400);
DISPLAY 0.617021 (3850 -400);
PAINT GREEN (3850 -400);
DISPLAY INVISIBLE (3850 -400);
FORCEPROP 1 LAST VALUE IND-120NH-30-GP
J 0
(3700 -500);
DISPLAY 0.617021 (3700 -500);
PAINT GREEN (3700 -500);
DISPLAY INVISIBLE (3700 -500);
FORCEPROP 0 LAST ATTRIBUTE 120NH
J 0
(3700 -550);
DISPLAY 0.638298 (3700 -550);
PAINT GREEN (3700 -550);
DISPLAY INVISIBLE (3700 -550);
FORCEPROP 0 LAST RATED ISAT=94A@25C
J 0
(3700 -600);
DISPLAY 0.638298 (3700 -600);
PAINT GREEN (3700 -600);
DISPLAY INVISIBLE (3700 -600);
FORCEPROP 0 LAST PACK_SIZE DCR=0.17MOHM
J 0
(3700 -700);
DISPLAY 0.638298 (3700 -700);
PAINT GREEN (3700 -700);
DISPLAY INVISIBLE (3700 -700);
FORCEPROP 0 LAST TYPE IRMS=66A@DELTA_T<40C
J 0
(3700 -650);
DISPLAY 0.638298 (3700 -650);
PAINT GREEN (3700 -650);
DISPLAY INVISIBLE (3700 -650);
FORCEPROP 1 LAST PATH I158
R 1
J 0
(3850 -400);
DISPLAY 0.617021 (3850 -400);
PAINT GREEN (3850 -400);
DISPLAY INVISIBLE (3850 -400);
FORCEADD GND..1
(2300 1500);
FORCEPROP 3 LASTPIN (2300 1550) SIG_NAME GND\g
J 0
(2310 1560);
DISPLAY 0.659574 (2310 1560);
PAINT MONO (2310 1560);
DISPLAY INVISIBLE (2310 1560);
FORCEPROP 1 LAST HDL_POWER GND
J 0
(2300 1650);
DISPLAY 1.723404 (2300 1650);
PAINT GREEN (2300 1650);
DISPLAY INVISIBLE (2300 1650);
FORCEPROP 1 LAST BODY_TYPE PLUMBING
J 0
(2255 1457);
DISPLAY 0.340426 (2255 1457);
PAINT GREEN (2255 1457);
DISPLAY INVISIBLE (2255 1457);
FORCEPROP 2 LAST ROOM VDDQ_DEF_PWR_VR
J 0
(1750 1575);
DISPLAY 1.936170 (1750 1575);
PAINT ORANGE (1750 1575);
DISPLAY INVISIBLE (1750 1575);
FORCEPROP 2 LAST BOM_COST PROC_VRD_VCCIN_CPU0
J 0
(1925 1575);
DISPLAY 1.446809 (1925 1575);
PAINT MONO (1925 1575);
DISPLAY INVISIBLE (1925 1575);
FORCEPROP 1 LAST SIZE 1B
J 0
(2375 1450);
DISPLAY 1.723404 (2375 1450);
PAINT GREEN (2375 1450);
DISPLAY INVISIBLE (2375 1450);
FORCEPROP 2 LAST CDS_LIB mstr_symbols
J 0
(2300 1500);
DISPLAY 1.936170 (2300 1500);
PAINT ORANGE (2300 1500);
DISPLAY INVISIBLE (2300 1500);
FORCEPROP 1 LAST VOLTAGE 0
J 0
(2300 1500);
PAINT SKYBLUE (2300 1500);
DISPLAY INVISIBLE (2300 1500);
FORCEPROP 1 LAST PATH I19
J 0
(2375 1500);
DISPLAY 0.893617 (2375 1500);
PAINT AQUA (2375 1500);
DISPLAY INVISIBLE (2375 1500);
FORCEADD OFFPAGE..2
(3800 2675);
FORCEPROP 2 LAST $XR0 218 
J 0
(3989 2675);
DISPLAY 0.638298 (3989 2675);
PAINT MONO (3989 2675);
FORCEPROP 1 LAST COMMENT_BODY TRUE
J 0
(3755 2580);
DISPLAY 1.723404 (3755 2580);
PAINT GREEN (3755 2580);
DISPLAY INVISIBLE (3755 2580);
FORCEPROP 1 LAST OFFPAGE TRUE
J 0
(4125 2550);
DISPLAY 1.723404 (4125 2550);
PAINT GREEN (4125 2550);
DISPLAY INVISIBLE (4125 2550);
FORCEPROP 2 LAST ROOM VDDQ_DEF_PWR_VR
J 0
(3400 2750);
DISPLAY 1.936170 (3400 2750);
PAINT ORANGE (3400 2750);
DISPLAY INVISIBLE (3400 2750);
FORCEPROP 2 LAST CDS_LIB mstr_standard
J 0
(3800 2675);
DISPLAY 1.936170 (3800 2675);
PAINT ORANGE (3800 2675);
DISPLAY INVISIBLE (3800 2675);
FORCEPROP 2 LAST PATH I3
J 0
(3990 2725);
DISPLAY 1.021277 (3990 2725);
PAINT ORANGE (3990 2725);
DISPLAY INVISIBLE (3990 2725);
FORCEPROP 2 LAST BOM_COST PROC_VRD_VCCIN_CPU0
J 0
(4000 2725);
DISPLAY 1.446809 (4000 2725);
PAINT MONO (4000 2725);
DISPLAY INVISIBLE (4000 2725);
FORCEADD OFFPAGE..1
(-1500 2025);
FORCEPROP 2 LASTPIN (-1450 2025) SIG_NAME VR_PVDDQ_DEF_PWM1
J 0
(-1435 2035);
DISPLAY 0.617021 (-1435 2035);
PAINT ORANGE (-1435 2035);
FORCEPROP 2 LAST $XR0 218 
J 0
(-1752 2025);
DISPLAY 0.638298 (-1752 2025);
PAINT MONO (-1752 2025);
FORCEPROP 1 LAST COMMENT_BODY TRUE
J 0
(-1375 1925);
DISPLAY 1.680851 (-1375 1925);
PAINT GREEN (-1375 1925);
DISPLAY INVISIBLE (-1375 1925);
FORCEPROP 1 LAST OFFPAGE TRUE
J 0
(-1175 1900);
DISPLAY 1.680851 (-1175 1900);
PAINT GREEN (-1175 1900);
DISPLAY INVISIBLE (-1175 1900);
FORCEPROP 2 LAST ROOM VDDQ_DEF_PWR_VR
J 0
(-1900 2100);
DISPLAY 1.936170 (-1900 2100);
PAINT ORANGE (-1900 2100);
DISPLAY INVISIBLE (-1900 2100);
FORCEPROP 2 LAST PATH I33
J 0
(-1780 2075);
DISPLAY 1.021277 (-1780 2075);
PAINT ORANGE (-1780 2075);
DISPLAY INVISIBLE (-1780 2075);
FORCEPROP 2 LAST CDS_LIB mstr_standard
J 0
(-1500 2025);
DISPLAY 1.936170 (-1500 2025);
PAINT ORANGE (-1500 2025);
DISPLAY INVISIBLE (-1500 2025);
FORCEPROP 2 LAST BOM_COST PROC_VRD_VCCIN_CPU0
J 0
(-1750 2075);
DISPLAY 1.446809 (-1750 2075);
PAINT MONO (-1750 2075);
DISPLAY INVISIBLE (-1750 2075);
FORCEADD GND..1
(-2225 2000);
FORCEPROP 3 LASTPIN (-2225 2050) SIG_NAME GND\g
J 0
(-2215 2060);
DISPLAY 0.659574 (-2215 2060);
PAINT MONO (-2215 2060);
DISPLAY INVISIBLE (-2215 2060);
FORCEPROP 1 LAST HDL_POWER GND
J 0
(-2225 2150);
DISPLAY 1.723404 (-2225 2150);
PAINT GREEN (-2225 2150);
DISPLAY INVISIBLE (-2225 2150);
FORCEPROP 1 LAST BODY_TYPE PLUMBING
J 0
(-2270 1957);
DISPLAY 0.340426 (-2270 1957);
PAINT GREEN (-2270 1957);
DISPLAY INVISIBLE (-2270 1957);
FORCEPROP 2 LAST BOM_COST PROC_VRD_VCCIN_CPU0
J 0
(-2600 2075);
DISPLAY 1.446809 (-2600 2075);
PAINT MONO (-2600 2075);
DISPLAY INVISIBLE (-2600 2075);
FORCEPROP 2 LAST ROOM VDDQ_DEF_PWR_VR
J 0
(-2775 2075);
DISPLAY 1.936170 (-2775 2075);
PAINT ORANGE (-2775 2075);
DISPLAY INVISIBLE (-2775 2075);
FORCEPROP 1 LAST VOLTAGE 0
J 0
(-2225 2000);
PAINT SKYBLUE (-2225 2000);
DISPLAY INVISIBLE (-2225 2000);
FORCEPROP 2 LAST CDS_LIB mstr_symbols
J 0
(-2225 2000);
DISPLAY 1.936170 (-2225 2000);
PAINT ORANGE (-2225 2000);
DISPLAY INVISIBLE (-2225 2000);
FORCEPROP 1 LAST SIZE 1B
J 0
(-2150 1950);
DISPLAY 1.723404 (-2150 1950);
PAINT GREEN (-2150 1950);
DISPLAY INVISIBLE (-2150 1950);
FORCEPROP 1 LAST PATH I35
J 0
(-2150 2000);
DISPLAY 0.893617 (-2150 2000);
PAINT AQUA (-2150 2000);
DISPLAY INVISIBLE (-2150 2000);
FORCEADD OFFPAGE..2
(3825 3000);
FORCEPROP 2 LAST $XR0 218 
J 0
(4014 3000);
DISPLAY 0.638298 (4014 3000);
PAINT MONO (4014 3000);
FORCEPROP 1 LAST COMMENT_BODY TRUE
J 0
(3780 2905);
DISPLAY 1.723404 (3780 2905);
PAINT GREEN (3780 2905);
DISPLAY INVISIBLE (3780 2905);
FORCEPROP 1 LAST OFFPAGE TRUE
J 0
(4150 2875);
DISPLAY 1.723404 (4150 2875);
PAINT GREEN (4150 2875);
DISPLAY INVISIBLE (4150 2875);
FORCEPROP 2 LAST CDS_LIB mstr_standard
J 2
(3825 3000);
DISPLAY 1.936170 (3825 3000);
PAINT ORANGE (3825 3000);
DISPLAY INVISIBLE (3825 3000);
FORCEPROP 2 LAST PATH I4
J 0
(4015 3050);
DISPLAY 1.021277 (4015 3050);
PAINT ORANGE (4015 3050);
DISPLAY INVISIBLE (4015 3050);
FORCEPROP 2 LAST BOM_COST PROC_VRD_VCCIN_CPU0
J 0
(4025 3050);
DISPLAY 1.446809 (4025 3050);
PAINT MONO (4025 3050);
DISPLAY INVISIBLE (4025 3050);
FORCEPROP 2 LAST ROOM VDDQ_DEF_PWR_VR
J 0
(3425 3075);
DISPLAY 1.936170 (3425 3075);
PAINT ORANGE (3425 3075);
DISPLAY INVISIBLE (3425 3075);
FORCEADD CAP..1
R 2
(-1100 1775);
FORCEPROP 1 LAST LOCATION C7A12
J 2
(-1150 1875);
DISPLAY 0.617021 (-1150 1875);
PAINT AQUA (-1150 1875);
FORCEPROP 1 LAST PART_NUMBER A36096-104
J 2
(-1150 1625);
DISPLAY 0.617021 (-1150 1625);
PAINT BLUE (-1150 1625);
FORCEPROP 1 LAST VOLTAGE 16V
J 2
(-1150 1775);
DISPLAY 0.617021 (-1150 1775);
PAINT SKYBLUE (-1150 1775);
FORCEPROP 1 LAST PACK_TYPE 0402
J 2
(-1150 1575);
DISPLAY 0.617021 (-1150 1575);
PAINT SKYBLUE (-1150 1575);
FORCEPROP 1 LASTPIN (-1100 1875) $PN 1
J 2
(-1110 1855);
DISPLAY 0.617021 (-1110 1855);
PAINT ORANGE (-1110 1855);
FORCEPROP 1 LASTPIN (-1100 1675) $PN 2
J 2
(-1110 1655);
DISPLAY 0.617021 (-1110 1655);
PAINT ORANGE (-1110 1655);
FORCEPROP 1 LAST TOLERANCE 10%
J 2
(-1150 1725);
DISPLAY 0.617021 (-1150 1725);
PAINT SKYBLUE (-1150 1725);
FORCEPROP 1 LAST MATERIAL X7R
J 2
(-1150 1675);
DISPLAY 0.617021 (-1150 1675);
PAINT SKYBLUE (-1150 1675);
FORCEPROP 1 LAST VALUE 0.220UF
J 2
(-1150 1825);
DISPLAY 0.617021 (-1150 1825);
PAINT SKYBLUE (-1150 1825);
FORCEPROP 2 LAST CDS_LIB mstr_discrete
J 0
(-1100 1775);
PAINT ORANGE (-1100 1775);
DISPLAY INVISIBLE (-1100 1775);
FORCEPROP 0 LAST SPOF TRUE
J 0
(-1150 1975);
DISPLAY 1.021277 (-1150 1975);
PAINT ORANGE (-1150 1975);
DISPLAY INVISIBLE (-1150 1975);
FORCEPROP 2 LAST CDS_LOCATION C7A12
J 2
(-1150 1875);
DISPLAY 0.617021 (-1150 1875);
PAINT AQUA (-1150 1875);
DISPLAY INVISIBLE (-1150 1875);
FORCEPROP 2 LAST ROOM VDDQ_DEF_PWR_VR
J 0
(-1175 1925);
DISPLAY 1.361702 (-1175 1925);
PAINT ORANGE (-1175 1925);
DISPLAY INVISIBLE (-1175 1925);
FORCEPROP 1 LAST PATH I44
J 2
(-1150 1925);
DISPLAY 0.978723 (-1150 1925);
PAINT WHITE (-1150 1925);
DISPLAY INVISIBLE (-1150 1925);
FORCEPROP 2 LAST SEC 1
J 0
(-1150 1975);
PAINT MONO (-1150 1975);
DISPLAY INVISIBLE (-1150 1975);
FORCEPROP 2 LAST SEC_TYPE 0402
J 0
(-1150 1975);
DISPLAY 1.021277 (-1150 1975);
PAINT ORANGE (-1150 1975);
DISPLAY INVISIBLE (-1150 1975);
FORCEADD CAP..1
(-2225 2425);
FORCEPROP 1 LAST VALUE 10UF
J 0
(-2175 2475);
DISPLAY 0.617021 (-2175 2475);
PAINT SKYBLUE (-2175 2475);
FORCEPROP 1 LAST LOCATION C3L2
J 0
(-2175 2525);
DISPLAY 0.617021 (-2175 2525);
PAINT AQUA (-2175 2525);
FORCEPROP 1 LAST MATERIAL X6S
J 0
(-2175 2325);
DISPLAY 0.617021 (-2175 2325);
PAINT SKYBLUE (-2175 2325);
FORCEPROP 1 LAST TOLERANCE 10%
J 0
(-2175 2375);
DISPLAY 0.617021 (-2175 2375);
PAINT SKYBLUE (-2175 2375);
FORCEPROP 1 LAST VOLTAGE 16V
J 0
(-2175 2425);
DISPLAY 0.617021 (-2175 2425);
PAINT SKYBLUE (-2175 2425);
FORCEPROP 1 LAST PART_NUMBER C95333-007
J 0
(-2175 2275);
DISPLAY 0.617021 (-2175 2275);
PAINT BLUE (-2175 2275);
FORCEPROP 1 LAST PACK_TYPE 0805
J 0
(-2175 2225);
DISPLAY 0.617021 (-2175 2225);
PAINT SKYBLUE (-2175 2225);
FORCEPROP 1 LASTPIN (-2225 2525) $PN 1
J 0
(-2215 2505);
DISPLAY 1.063830 (-2215 2505);
PAINT ORANGE (-2215 2505);
FORCEPROP 1 LASTPIN (-2225 2325) $PN 2
J 0
(-2215 2305);
DISPLAY 1.063830 (-2215 2305);
PAINT ORANGE (-2215 2305);
FORCEPROP 1 LAST PATH I45
J 0
(-2175 2575);
DISPLAY 1.319149 (-2175 2575);
PAINT WHITE (-2175 2575);
DISPLAY INVISIBLE (-2175 2575);
FORCEPROP 2 LAST ROOM VDDQ_DEF_PWR_VR
J 0
(-2175 2575);
DISPLAY 1.361702 (-2175 2575);
PAINT ORANGE (-2175 2575);
DISPLAY INVISIBLE (-2175 2575);
FORCEPROP 2 LAST CDS_LOCATION C3L2
J 0
(-2175 2525);
DISPLAY 0.617021 (-2175 2525);
PAINT AQUA (-2175 2525);
DISPLAY INVISIBLE (-2175 2525);
FORCEPROP 2 LAST CDS_LIB mstr_discrete
J 0
(-2225 2425);
PAINT ORANGE (-2225 2425);
DISPLAY INVISIBLE (-2225 2425);
FORCEPROP 2 LAST SEC 1
J 0
(-2175 2650);
DISPLAY 0.680851 (-2175 2650);
PAINT MONO (-2175 2650);
DISPLAY INVISIBLE (-2175 2650);
FORCEPROP 2 LAST SEC_TYPE 0805
J 0
(-2175 2650);
DISPLAY 1.021277 (-2175 2650);
PAINT ORANGE (-2175 2650);
DISPLAY INVISIBLE (-2175 2650);
FORCEADD CAP..1
(-2000 2425);
FORCEPROP 1 LAST VOLTAGE 16V
J 0
(-1950 2425);
DISPLAY 0.617021 (-1950 2425);
PAINT SKYBLUE (-1950 2425);
FORCEPROP 1 LAST TOLERANCE 10%
J 0
(-1950 2375);
DISPLAY 0.617021 (-1950 2375);
PAINT SKYBLUE (-1950 2375);
FORCEPROP 1 LAST MATERIAL X6S
J 0
(-1950 2325);
DISPLAY 0.617021 (-1950 2325);
PAINT SKYBLUE (-1950 2325);
FORCEPROP 1 LAST PART_NUMBER C95333-007
J 0
(-1950 2275);
DISPLAY 0.617021 (-1950 2275);
PAINT BLUE (-1950 2275);
FORCEPROP 1 LAST VALUE 10UF
J 0
(-1950 2475);
DISPLAY 0.617021 (-1950 2475);
PAINT SKYBLUE (-1950 2475);
FORCEPROP 1 LAST PACK_TYPE 0805
J 0
(-1950 2225);
DISPLAY 0.617021 (-1950 2225);
PAINT SKYBLUE (-1950 2225);
FORCEPROP 1 LASTPIN (-2000 2525) $PN 1
J 0
(-1990 2505);
DISPLAY 1.063830 (-1990 2505);
PAINT ORANGE (-1990 2505);
FORCEPROP 1 LASTPIN (-2000 2325) $PN 2
J 0
(-1990 2305);
DISPLAY 1.063830 (-1990 2305);
PAINT ORANGE (-1990 2305);
FORCEPROP 1 LAST LOCATION C3L4
J 0
(-1950 2525);
DISPLAY 0.617021 (-1950 2525);
PAINT AQUA (-1950 2525);
FORCEPROP 2 LAST CDS_LIB mstr_discrete
J 0
(-2000 2425);
PAINT ORANGE (-2000 2425);
DISPLAY INVISIBLE (-2000 2425);
FORCEPROP 2 LAST CDS_LOCATION C3L4
J 0
(-1950 2525);
DISPLAY 0.617021 (-1950 2525);
PAINT AQUA (-1950 2525);
DISPLAY INVISIBLE (-1950 2525);
FORCEPROP 2 LAST ROOM VDDQ_DEF_PWR_VR
J 0
(-1950 2575);
DISPLAY 1.361702 (-1950 2575);
PAINT ORANGE (-1950 2575);
DISPLAY INVISIBLE (-1950 2575);
FORCEPROP 1 LAST PATH I46
J 0
(-1950 2575);
DISPLAY 1.319149 (-1950 2575);
PAINT WHITE (-1950 2575);
DISPLAY INVISIBLE (-1950 2575);
FORCEPROP 2 LAST SEC 1
J 0
(-1950 2650);
DISPLAY 0.680851 (-1950 2650);
PAINT MONO (-1950 2650);
DISPLAY INVISIBLE (-1950 2650);
FORCEPROP 2 LAST SEC_TYPE 0805
J 0
(-1950 2650);
DISPLAY 1.021277 (-1950 2650);
PAINT ORANGE (-1950 2650);
DISPLAY INVISIBLE (-1950 2650);
FORCEADD CAP..1
(-1775 2425);
FORCEPROP 1 LAST VALUE 10UF
J 0
(-1725 2475);
DISPLAY 0.617021 (-1725 2475);
PAINT SKYBLUE (-1725 2475);
FORCEPROP 1 LAST PART_NUMBER C95333-007
J 0
(-1725 2275);
DISPLAY 0.617021 (-1725 2275);
PAINT BLUE (-1725 2275);
FORCEPROP 1 LASTPIN (-1775 2325) $PN 2
J 0
(-1765 2305);
DISPLAY 1.063830 (-1765 2305);
PAINT ORANGE (-1765 2305);
FORCEPROP 1 LAST MATERIAL X6S
J 0
(-1725 2325);
DISPLAY 0.617021 (-1725 2325);
PAINT SKYBLUE (-1725 2325);
FORCEPROP 1 LAST TOLERANCE 10%
J 0
(-1725 2375);
DISPLAY 0.617021 (-1725 2375);
PAINT SKYBLUE (-1725 2375);
FORCEPROP 1 LASTPIN (-1775 2525) $PN 1
J 0
(-1765 2505);
DISPLAY 1.063830 (-1765 2505);
PAINT ORANGE (-1765 2505);
FORCEPROP 1 LAST PACK_TYPE 0805
J 0
(-1725 2225);
DISPLAY 0.617021 (-1725 2225);
PAINT SKYBLUE (-1725 2225);
FORCEPROP 1 LAST VOLTAGE 16V
J 0
(-1725 2425);
DISPLAY 0.617021 (-1725 2425);
PAINT SKYBLUE (-1725 2425);
FORCEPROP 1 LAST LOCATION C3L13
J 0
(-1725 2525);
DISPLAY 0.617021 (-1725 2525);
PAINT AQUA (-1725 2525);
FORCEPROP 1 LAST PATH I47
J 0
(-1725 2575);
DISPLAY 1.319149 (-1725 2575);
PAINT WHITE (-1725 2575);
DISPLAY INVISIBLE (-1725 2575);
FORCEPROP 2 LAST ROOM VDDQ_DEF_PWR_VR
J 0
(-1725 2575);
DISPLAY 1.361702 (-1725 2575);
PAINT ORANGE (-1725 2575);
DISPLAY INVISIBLE (-1725 2575);
FORCEPROP 2 LAST CDS_LOCATION C3L13
J 0
(-1725 2525);
DISPLAY 0.617021 (-1725 2525);
PAINT AQUA (-1725 2525);
DISPLAY INVISIBLE (-1725 2525);
FORCEPROP 2 LAST CDS_LIB mstr_discrete
J 0
(-1775 2425);
PAINT ORANGE (-1775 2425);
DISPLAY INVISIBLE (-1775 2425);
FORCEPROP 2 LAST SEC 1
J 0
(-1725 2650);
DISPLAY 0.680851 (-1725 2650);
PAINT MONO (-1725 2650);
DISPLAY INVISIBLE (-1725 2650);
FORCEPROP 2 LAST SEC_TYPE 0805
J 0
(-1725 2650);
DISPLAY 1.021277 (-1725 2650);
PAINT ORANGE (-1725 2650);
DISPLAY INVISIBLE (-1725 2650);
FORCEADD CAP..1
(-1475 2425);
FORCEPROP 1 LAST VALUE 1.0UF
J 0
(-1425 2475);
DISPLAY 0.617021 (-1425 2475);
PAINT SKYBLUE (-1425 2475);
FORCEPROP 1 LAST PACK_TYPE 0402
J 0
(-1425 2225);
DISPLAY 0.617021 (-1425 2225);
PAINT SKYBLUE (-1425 2225);
FORCEPROP 1 LAST TOLERANCE 10%
J 0
(-1425 2375);
DISPLAY 0.617021 (-1425 2375);
PAINT SKYBLUE (-1425 2375);
FORCEPROP 1 LAST VOLTAGE 16V
J 0
(-1425 2425);
DISPLAY 0.617021 (-1425 2425);
PAINT SKYBLUE (-1425 2425);
FORCEPROP 1 LAST LOCATION C7A11
J 0
(-1425 2525);
DISPLAY 0.617021 (-1425 2525);
PAINT AQUA (-1425 2525);
FORCEPROP 1 LASTPIN (-1475 2525) $PN 1
J 0
(-1465 2505);
DISPLAY 1.063830 (-1465 2505);
PAINT ORANGE (-1465 2505);
FORCEPROP 1 LASTPIN (-1475 2325) $PN 2
J 0
(-1465 2305);
DISPLAY 1.063830 (-1465 2305);
PAINT ORANGE (-1465 2305);
FORCEPROP 1 LAST MATERIAL X6S
J 0
(-1425 2325);
DISPLAY 0.617021 (-1425 2325);
PAINT SKYBLUE (-1425 2325);
FORCEPROP 1 LAST PART_NUMBER D97712-011
J 0
(-1425 2275);
DISPLAY 0.617021 (-1425 2275);
PAINT BLUE (-1425 2275);
FORCEPROP 1 LAST PATH I48
J 0
(-1425 2575);
DISPLAY 1.319149 (-1425 2575);
PAINT WHITE (-1425 2575);
DISPLAY INVISIBLE (-1425 2575);
FORCEPROP 2 LAST ROOM VDDQ_DEF_PWR_VR
J 0
(-1425 2575);
DISPLAY 1.361702 (-1425 2575);
PAINT ORANGE (-1425 2575);
DISPLAY INVISIBLE (-1425 2575);
FORCEPROP 2 LAST CDS_LOCATION C7A11
J 0
(-1425 2525);
DISPLAY 0.617021 (-1425 2525);
PAINT AQUA (-1425 2525);
DISPLAY INVISIBLE (-1425 2525);
FORCEPROP 2 LAST CDS_LIB mstr_discrete
J 0
(-1475 2425);
PAINT ORANGE (-1475 2425);
DISPLAY INVISIBLE (-1475 2425);
FORCEPROP 2 LAST SEC 1
J 0
(-1425 2650);
DISPLAY 0.680851 (-1425 2650);
PAINT MONO (-1425 2650);
DISPLAY INVISIBLE (-1425 2650);
FORCEPROP 2 LAST SEC_TYPE 0402
J 0
(-1425 2650);
DISPLAY 1.021277 (-1425 2650);
PAINT ORANGE (-1425 2650);
DISPLAY INVISIBLE (-1425 2650);
FORCEADD CAP..1
(-875 2425);
FORCEPROP 1 LASTPIN (-875 2525) $PN 1
J 0
(-865 2505);
DISPLAY 1.063830 (-865 2505);
PAINT ORANGE (-865 2505);
FORCEPROP 1 LASTPIN (-875 2325) $PN 2
J 0
(-865 2305);
DISPLAY 1.063830 (-865 2305);
PAINT ORANGE (-865 2305);
FORCEPROP 1 LAST PACK_TYPE 0402
J 0
(-825 2225);
DISPLAY 0.617021 (-825 2225);
PAINT SKYBLUE (-825 2225);
FORCEPROP 1 LAST MATERIAL X6S
J 0
(-825 2325);
DISPLAY 0.617021 (-825 2325);
PAINT SKYBLUE (-825 2325);
FORCEPROP 1 LAST TOLERANCE 10%
J 0
(-825 2375);
DISPLAY 0.617021 (-825 2375);
PAINT SKYBLUE (-825 2375);
FORCEPROP 1 LAST LOCATION C7A16
J 0
(-825 2525);
DISPLAY 0.617021 (-825 2525);
PAINT AQUA (-825 2525);
FORCEPROP 1 LAST VALUE 1.0UF
J 0
(-825 2475);
DISPLAY 0.617021 (-825 2475);
PAINT SKYBLUE (-825 2475);
FORCEPROP 1 LAST PART_NUMBER D97712-011
J 0
(-825 2275);
DISPLAY 0.617021 (-825 2275);
PAINT BLUE (-825 2275);
FORCEPROP 1 LAST VOLTAGE 16V
J 0
(-825 2425);
DISPLAY 0.617021 (-825 2425);
PAINT SKYBLUE (-825 2425);
FORCEPROP 2 LAST ROOM VDDQ_DEF_PWR_VR
J 0
(-825 2575);
DISPLAY 1.361702 (-825 2575);
PAINT ORANGE (-825 2575);
DISPLAY INVISIBLE (-825 2575);
FORCEPROP 1 LAST PATH I50
J 0
(-825 2575);
DISPLAY 1.319149 (-825 2575);
PAINT WHITE (-825 2575);
DISPLAY INVISIBLE (-825 2575);
FORCEPROP 2 LAST CDS_LOCATION C7A16
J 0
(-825 2525);
DISPLAY 0.617021 (-825 2525);
PAINT AQUA (-825 2525);
DISPLAY INVISIBLE (-825 2525);
FORCEPROP 2 LAST CDS_LIB mstr_discrete
J 0
(-875 2425);
PAINT ORANGE (-875 2425);
DISPLAY INVISIBLE (-875 2425);
FORCEPROP 2 LAST SEC 1
J 0
(-825 2650);
DISPLAY 0.680851 (-825 2650);
PAINT MONO (-825 2650);
DISPLAY INVISIBLE (-825 2650);
FORCEPROP 2 LAST SEC_TYPE 0402
J 0
(-825 2650);
DISPLAY 1.021277 (-825 2650);
PAINT ORANGE (-825 2650);
DISPLAY INVISIBLE (-825 2650);
FORCEADD CAP_A..1
(-1175 2425);
FORCEPROP 1 LAST LOCATION C7A5
J 0
(-1125 2525);
DISPLAY 0.617021 (-1125 2525);
PAINT AQUA (-1125 2525);
FORCEPROP 1 LAST PART_NUMBER A36096-030
J 0
(-1125 2275);
DISPLAY 0.617021 (-1125 2275);
PAINT BLUE (-1125 2275);
FORCEPROP 1 LASTPIN (-1175 2325) $PN 2
J 0
(-1165 2305);
DISPLAY 1.063830 (-1165 2305);
PAINT ORANGE (-1165 2305);
FORCEPROP 1 LAST MATERIAL X7R
J 0
(-1125 2325);
DISPLAY 0.617021 (-1125 2325);
PAINT SKYBLUE (-1125 2325);
FORCEPROP 1 LAST TOLERANCE 10%
J 0
(-1125 2375);
DISPLAY 0.617021 (-1125 2375);
PAINT SKYBLUE (-1125 2375);
FORCEPROP 1 LAST VOLTAGE 16V
J 0
(-1125 2425);
DISPLAY 0.617021 (-1125 2425);
PAINT SKYBLUE (-1125 2425);
FORCEPROP 1 LAST VALUE 0.1UF
J 0
(-1125 2475);
DISPLAY 0.617021 (-1125 2475);
PAINT SKYBLUE (-1125 2475);
FORCEPROP 1 LASTPIN (-1175 2525) $PN 1
J 0
(-1165 2505);
DISPLAY 1.063830 (-1165 2505);
PAINT ORANGE (-1165 2505);
FORCEPROP 1 LAST PACK_TYPE 0402V
J 0
(-1125 2225);
DISPLAY 0.617021 (-1125 2225);
PAINT SKYBLUE (-1125 2225);
FORCEPROP 2 LAST CDS_LIB dev_discrete
J 0
(-1175 2425);
PAINT ORANGE (-1175 2425);
DISPLAY INVISIBLE (-1175 2425);
FORCEPROP 2 LAST CDS_LOCATION C7A5
J 0
(-1125 2525);
DISPLAY 0.617021 (-1125 2525);
PAINT AQUA (-1125 2525);
DISPLAY INVISIBLE (-1125 2525);
FORCEPROP 2 LAST ROOM VDDQ_DEF_PWR_VR
J 0
(-1125 2575);
DISPLAY 1.361702 (-1125 2575);
PAINT ORANGE (-1125 2575);
DISPLAY INVISIBLE (-1125 2575);
FORCEPROP 1 LAST PATH I51
J 0
(-1125 2575);
DISPLAY 0.978723 (-1125 2575);
PAINT WHITE (-1125 2575);
DISPLAY INVISIBLE (-1125 2575);
FORCEPROP 2 LAST SEC 1
J 0
(-1125 2650);
DISPLAY 0.680851 (-1125 2650);
PAINT MONO (-1125 2650);
DISPLAY INVISIBLE (-1125 2650);
FORCEPROP 2 LAST SEC_TYPE 0402V
J 0
(-1125 2625);
DISPLAY 1.021277 (-1125 2625);
PAINT ORANGE (-1125 2625);
DISPLAY INVISIBLE (-1125 2625);
FORCEADD CAP..1
(-125 2425);
FORCEPROP 1 LAST VALUE 0.22UF
J 0
(-75 2475);
DISPLAY 0.617021 (-75 2475);
PAINT SKYBLUE (-75 2475);
FORCEPROP 1 LAST LOCATION C7A17
J 0
(-75 2525);
DISPLAY 0.617021 (-75 2525);
PAINT AQUA (-75 2525);
FORCEPROP 1 LASTPIN (-125 2525) $PN 1
J 0
(-115 2505);
DISPLAY 0.851064 (-115 2505);
PAINT ORANGE (-115 2505);
FORCEPROP 1 LAST VOLTAGE 16V
J 0
(-75 2425);
DISPLAY 0.617021 (-75 2425);
PAINT SKYBLUE (-75 2425);
FORCEPROP 1 LASTPIN (-125 2325) $PN 2
J 0
(-115 2305);
DISPLAY 0.851064 (-115 2305);
PAINT ORANGE (-115 2305);
FORCEPROP 1 LAST TOLERANCE 10%
J 0
(-75 2375);
DISPLAY 0.617021 (-75 2375);
PAINT SKYBLUE (-75 2375);
FORCEPROP 1 LAST PART_NUMBER A36096-155
J 0
(-75 2275);
DISPLAY 0.617021 (-75 2275);
PAINT BLUE (-75 2275);
FORCEPROP 1 LAST PACK_TYPE 0402
J 0
(-75 2225);
DISPLAY 0.617021 (-75 2225);
PAINT SKYBLUE (-75 2225);
FORCEPROP 1 LAST MATERIAL X7R
J 0
(-75 2325);
DISPLAY 0.617021 (-75 2325);
PAINT SKYBLUE (-75 2325);
FORCEPROP 2 LAST CDS_LOCATION C7A17
J 0
(-75 2525);
DISPLAY 0.617021 (-75 2525);
PAINT AQUA (-75 2525);
DISPLAY INVISIBLE (-75 2525);
FORCEPROP 2 LAST CDS_LIB mstr_discrete
J 0
(-125 2425);
PAINT ORANGE (-125 2425);
DISPLAY INVISIBLE (-125 2425);
FORCEPROP 1 LAST PATH I54
J 0
(-75 2575);
DISPLAY 1.319149 (-75 2575);
PAINT WHITE (-75 2575);
DISPLAY INVISIBLE (-75 2575);
FORCEPROP 2 LAST ROOM VDDQ_DEF_PWR_VR
J 0
(-75 2575);
DISPLAY 1.361702 (-75 2575);
PAINT ORANGE (-75 2575);
DISPLAY INVISIBLE (-75 2575);
FORCEPROP 2 LAST SEC 1
J 0
(-75 2650);
DISPLAY 0.680851 (-75 2650);
PAINT MONO (-75 2650);
DISPLAY INVISIBLE (-75 2650);
FORCEPROP 2 LAST SEC_TYPE 0402
J 0
(-75 2650);
DISPLAY 1.021277 (-75 2650);
PAINT ORANGE (-75 2650);
DISPLAY INVISIBLE (-75 2650);
FORCEADD OFFPAGE..2
(3425 2300);
FORCEPROP 2 LAST $XR1 218 
J 0
(3734 2300);
DISPLAY 0.638298 (3734 2300);
PAINT MONO (3734 2300);
FORCEPROP 2 LAST $XR0 219 
J 0
(3614 2300);
DISPLAY 0.638298 (3614 2300);
PAINT MONO (3614 2300);
FORCEPROP 1 LAST COMMENT_BODY TRUE
J 0
(3380 2205);
DISPLAY 1.723404 (3380 2205);
PAINT GREEN (3380 2205);
DISPLAY INVISIBLE (3380 2205);
FORCEPROP 1 LAST OFFPAGE TRUE
J 0
(3750 2175);
DISPLAY 1.723404 (3750 2175);
PAINT GREEN (3750 2175);
DISPLAY INVISIBLE (3750 2175);
FORCEPROP 2 LAST BOM_COST PROC_VRD_VCCIN_CPU0
J 0
(3625 2350);
DISPLAY 1.446809 (3625 2350);
PAINT MONO (3625 2350);
DISPLAY INVISIBLE (3625 2350);
FORCEPROP 2 LAST PATH I58
J 0
(3605 2375);
DISPLAY 1.361702 (3605 2375);
PAINT ORANGE (3605 2375);
DISPLAY INVISIBLE (3605 2375);
FORCEPROP 2 LAST CDS_LIB mstr_standard
J 0
(3425 2300);
PAINT ORANGE (3425 2300);
DISPLAY INVISIBLE (3425 2300);
FORCEPROP 2 LAST ROOM VDDQ_DEF_PWR_VR
J 0
(3025 2375);
DISPLAY 1.936170 (3025 2375);
PAINT ORANGE (3025 2375);
DISPLAY INVISIBLE (3025 2375);
FORCEADD OFFPAGE..2
(3475 750);
FORCEPROP 2 LAST $XR0 218 
J 0
(3664 750);
DISPLAY 0.638298 (3664 750);
PAINT MONO (3664 750);
FORCEPROP 2 LAST BOM_COST PROC_VRD_VCCIN_CPU0
J 0
(3675 800);
DISPLAY 1.446809 (3675 800);
PAINT MONO (3675 800);
DISPLAY INVISIBLE (3675 800);
FORCEPROP 2 LAST PATH I61
J 0
(3655 825);
DISPLAY 1.361702 (3655 825);
PAINT ORANGE (3655 825);
DISPLAY INVISIBLE (3655 825);
FORCEPROP 2 LAST CDS_LIB mstr_standard
J 0
(3475 750);
PAINT ORANGE (3475 750);
DISPLAY INVISIBLE (3475 750);
FORCEPROP 2 LAST ROOM VDDQ_DEF_PWR_VR
J 0
(3075 825);
DISPLAY 1.936170 (3075 825);
PAINT ORANGE (3075 825);
DISPLAY INVISIBLE (3075 825);
FORCEPROP 1 LAST OFFPAGE TRUE
J 0
(3800 625);
DISPLAY 1.723404 (3800 625);
PAINT GREEN (3800 625);
DISPLAY INVISIBLE (3800 625);
FORCEPROP 1 LAST COMMENT_BODY TRUE
J 0
(3430 655);
DISPLAY 1.723404 (3430 655);
PAINT GREEN (3430 655);
DISPLAY INVISIBLE (3430 655);
FORCEADD OFFPAGE..2
(3550 425);
FORCEPROP 2 LAST $XR0 218 
J 0
(3739 425);
DISPLAY 0.638298 (3739 425);
PAINT MONO (3739 425);
FORCEPROP 2 LAST BOM_COST PROC_VRD_VCCIN_CPU0
J 0
(3750 475);
DISPLAY 1.446809 (3750 475);
PAINT MONO (3750 475);
DISPLAY INVISIBLE (3750 475);
FORCEPROP 2 LAST PATH I62
J 0
(3730 500);
DISPLAY 1.361702 (3730 500);
PAINT ORANGE (3730 500);
DISPLAY INVISIBLE (3730 500);
FORCEPROP 2 LAST CDS_LIB mstr_standard
J 0
(3550 425);
PAINT ORANGE (3550 425);
DISPLAY INVISIBLE (3550 425);
FORCEPROP 2 LAST ROOM VDDQ_DEF_PWR_VR
J 0
(3150 500);
DISPLAY 1.936170 (3150 500);
PAINT ORANGE (3150 500);
DISPLAY INVISIBLE (3150 500);
FORCEPROP 1 LAST OFFPAGE TRUE
J 0
(3875 300);
DISPLAY 1.723404 (3875 300);
PAINT GREEN (3875 300);
DISPLAY INVISIBLE (3875 300);
FORCEPROP 1 LAST COMMENT_BODY TRUE
J 0
(3505 330);
DISPLAY 1.723404 (3505 330);
PAINT GREEN (3505 330);
DISPLAY INVISIBLE (3505 330);
FORCEADD OFFPAGE..2
(3725 75);
FORCEPROP 2 LAST $XR1 218 
J 0
(4034 75);
DISPLAY 0.638298 (4034 75);
PAINT MONO (4034 75);
FORCEPROP 2 LAST $XR0 219 
J 0
(3914 75);
DISPLAY 0.638298 (3914 75);
PAINT MONO (3914 75);
FORCEPROP 2 LAST CDS_LIB mstr_standard
J 0
(3725 75);
PAINT ORANGE (3725 75);
DISPLAY INVISIBLE (3725 75);
FORCEPROP 2 LAST ROOM VDDQ_DEF_PWR_VR
J 0
(3325 150);
DISPLAY 1.936170 (3325 150);
PAINT ORANGE (3325 150);
DISPLAY INVISIBLE (3325 150);
FORCEPROP 2 LAST PATH I63
J 0
(3905 150);
DISPLAY 1.361702 (3905 150);
PAINT ORANGE (3905 150);
DISPLAY INVISIBLE (3905 150);
FORCEPROP 2 LAST BOM_COST PROC_VRD_VCCIN_CPU0
J 0
(3925 125);
DISPLAY 1.446809 (3925 125);
PAINT MONO (3925 125);
DISPLAY INVISIBLE (3925 125);
FORCEPROP 1 LAST OFFPAGE TRUE
J 0
(4050 -50);
DISPLAY 1.723404 (4050 -50);
PAINT GREEN (4050 -50);
DISPLAY INVISIBLE (4050 -50);
FORCEPROP 1 LAST COMMENT_BODY TRUE
J 0
(3680 -20);
DISPLAY 1.723404 (3680 -20);
PAINT GREEN (3680 -20);
DISPLAY INVISIBLE (3680 -20);
FORCEADD PVDDQ_DEF..1
(4500 -325);
FORCEPROP 3 LASTPIN (4500 -375) SIG_NAME PVDDQ_DEF\g
J 0
(4510 -365);
DISPLAY 0.659574 (4510 -365);
PAINT MONO (4510 -365);
DISPLAY INVISIBLE (4510 -365);
FORCEPROP 1 LAST HDL_POWER PVDDQ_DEF
J 1
(4500 -275);
DISPLAY 0.872340 (4500 -275);
PAINT GREEN (4500 -275);
DISPLAY INVISIBLE (4500 -275);
FORCEPROP 1 LAST BODY_TYPE PLUMBING
J 0
(4455 -368);
DISPLAY 0.340426 (4455 -368);
PAINT GREEN (4455 -368);
DISPLAY INVISIBLE (4455 -368);
FORCEPROP 1 LAST VOLTAGE 1.2V
J 0
(4455 -368);
DISPLAY 0.340426 (4455 -368);
PAINT SKYBLUE (4455 -368);
DISPLAY INVISIBLE (4455 -368);
FORCEPROP 2 LAST ROOM VDDQ_DEF_PWR_VR
J 0
(4500 -225);
DISPLAY 1.936170 (4500 -225);
PAINT ORANGE (4500 -225);
DISPLAY INVISIBLE (4500 -225);
FORCEPROP 1 LAST PATH I64
J 0
(4550 -300);
DISPLAY 0.872340 (4550 -300);
PAINT AQUA (4550 -300);
DISPLAY INVISIBLE (4550 -300);
FORCEPROP 2 LAST CDS_LIB mstr_symbols
J 0
(4500 -325);
PAINT ORANGE (4500 -325);
DISPLAY INVISIBLE (4500 -325);
FORCEPROP 2 LAST BOM_COST PROC_SOCKET 
J 0
(4500 -225);
DISPLAY 1.446809 (4500 -225);
PAINT MONO (4500 -225);
DISPLAY INVISIBLE (4500 -225);
FORCEADD CAP..1
(4500 -575);
FORCEPROP 1 LAST VOLTAGE 4V
J 0
(4550 -575);
DISPLAY 0.723404 (4550 -575);
PAINT SKYBLUE (4550 -575);
FORCEPROP 1 LAST LOCATION C6A4
J 0
(4550 -475);
DISPLAY 0.617021 (4550 -475);
PAINT AQUA (4550 -475);
FORCEPROP 0 LAST GROUP PWR_MLCC_CAP
J 0
(4556 -813);
DISPLAY 0.638298 (4556 -813);
PAINT BROWN (4556 -813);
DISPLAY BOTH (4556 -813);
FORCEPROP 1 LAST MATERIAL X6S
J 0
(4550 -675);
DISPLAY 0.617021 (4550 -675);
PAINT SKYBLUE (4550 -675);
FORCEPROP 1 LAST PART_NUMBER C95333-002
J 0
(4550 -725);
DISPLAY 0.617021 (4550 -725);
PAINT BLUE (4550 -725);
FORCEPROP 1 LASTPIN (4500 -475) $PN 1
J 0
(4510 -495);
DISPLAY 0.617021 (4510 -495);
PAINT ORANGE (4510 -495);
FORCEPROP 1 LAST PACK_TYPE 0805LF
J 0
(4550 -775);
DISPLAY 0.617021 (4550 -775);
PAINT SKYBLUE (4550 -775);
FORCEPROP 1 LASTPIN (4500 -675) $PN 2
J 0
(4510 -695);
DISPLAY 0.617021 (4510 -695);
PAINT ORANGE (4510 -695);
FORCEPROP 1 LAST VALUE 22UF
J 0
(4550 -525);
DISPLAY 0.617021 (4550 -525);
PAINT SKYBLUE (4550 -525);
FORCEPROP 0 LAST BOM_SS NOPOP
J 0
(4550 -850);
DISPLAY 0.638298 (4550 -850);
PAINT BROWN (4550 -850);
DISPLAY BOTH (4550 -850);
FORCEPROP 1 LAST TOLERANCE 20%
J 0
(4550 -625);
DISPLAY 0.617021 (4550 -625);
PAINT SKYBLUE (4550 -625);
FORCEPROP 2 LAST CDS_LIB mstr_discrete
J 0
(4500 -575);
PAINT ORANGE (4500 -575);
DISPLAY INVISIBLE (4500 -575);
FORCEPROP 2 LAST CDS_LOCATION C6A4
J 0
(4550 -475);
DISPLAY 0.617021 (4550 -475);
PAINT AQUA (4550 -475);
DISPLAY INVISIBLE (4550 -475);
FORCEPROP 2 LAST ROOM VDDQ_DEF_PWR_VR
J 0
(4550 -425);
DISPLAY 1.446809 (4550 -425);
PAINT MONO (4550 -425);
DISPLAY INVISIBLE (4550 -425);
FORCEPROP 1 LAST PATH I68
J 0
(4550 -425);
DISPLAY 1.319149 (4550 -425);
PAINT WHITE (4550 -425);
DISPLAY INVISIBLE (4550 -425);
FORCEPROP 2 LAST BOM_COST PROC_VRD_VCCIN_CPU0
J 0
(4550 -425);
DISPLAY 1.446809 (4550 -425);
PAINT MONO (4550 -425);
DISPLAY INVISIBLE (4550 -425);
FORCEPROP 2 LAST SEC 1
J 0
(4555 -350);
DISPLAY 0.680851 (4555 -350);
PAINT MONO (4555 -350);
DISPLAY INVISIBLE (4555 -350);
FORCEPROP 2 LAST SEC_TYPE 0805LF
J 0
(4555 -350);
DISPLAY 1.021277 (4555 -350);
PAINT ORANGE (4555 -350);
DISPLAY INVISIBLE (4555 -350);
FORCEADD GND..1
(4500 -750);
FORCEPROP 3 LASTPIN (4500 -700) SIG_NAME GND\g
J 0
(4510 -690);
DISPLAY 0.659574 (4510 -690);
PAINT MONO (4510 -690);
DISPLAY INVISIBLE (4510 -690);
FORCEPROP 1 LAST HDL_POWER GND
J 0
(4500 -600);
DISPLAY 1.723404 (4500 -600);
PAINT GREEN (4500 -600);
DISPLAY INVISIBLE (4500 -600);
FORCEPROP 1 LAST BODY_TYPE PLUMBING
J 0
(4455 -793);
DISPLAY 0.340426 (4455 -793);
PAINT GREEN (4455 -793);
DISPLAY INVISIBLE (4455 -793);
FORCEPROP 2 LAST ROOM VDDQ_DEF_PWR_VR
J 0
(3950 -675);
DISPLAY 1.936170 (3950 -675);
PAINT ORANGE (3950 -675);
DISPLAY INVISIBLE (3950 -675);
FORCEPROP 2 LAST BOM_COST PROC_VRD_VCCIN_CPU0
J 0
(4125 -675);
DISPLAY 1.446809 (4125 -675);
PAINT MONO (4125 -675);
DISPLAY INVISIBLE (4125 -675);
FORCEPROP 1 LAST PATH I69
J 0
(4575 -750);
DISPLAY 1.170213 (4575 -750);
PAINT AQUA (4575 -750);
DISPLAY INVISIBLE (4575 -750);
FORCEPROP 1 LAST SIZE 1B
J 0
(4575 -800);
DISPLAY 1.723404 (4575 -800);
PAINT GREEN (4575 -800);
DISPLAY INVISIBLE (4575 -800);
FORCEPROP 2 LAST CDS_LIB mstr_symbols
J 0
(4500 -750);
PAINT ORANGE (4500 -750);
DISPLAY INVISIBLE (4500 -750);
FORCEPROP 1 LAST VOLTAGE 0
J 0
(4500 -750);
PAINT SKYBLUE (4500 -750);
DISPLAY INVISIBLE (4500 -750);
FORCEADD GND..1
(4450 1500);
FORCEPROP 3 LASTPIN (4450 1550) SIG_NAME GND\g
J 0
(4460 1560);
DISPLAY 0.659574 (4460 1560);
PAINT MONO (4460 1560);
DISPLAY INVISIBLE (4460 1560);
FORCEPROP 1 LAST SIZE 1B
J 0
(4525 1450);
DISPLAY 1.723404 (4525 1450);
PAINT GREEN (4525 1450);
DISPLAY INVISIBLE (4525 1450);
FORCEPROP 1 LAST PATH I7
J 0
(4525 1500);
DISPLAY 0.893617 (4525 1500);
PAINT AQUA (4525 1500);
DISPLAY INVISIBLE (4525 1500);
FORCEPROP 2 LAST CDS_LIB mstr_symbols
J 0
(4450 1500);
DISPLAY 1.936170 (4450 1500);
PAINT ORANGE (4450 1500);
DISPLAY INVISIBLE (4450 1500);
FORCEPROP 1 LAST VOLTAGE 0
J 0
(4450 1500);
PAINT SKYBLUE (4450 1500);
DISPLAY INVISIBLE (4450 1500);
FORCEPROP 2 LAST BOM_COST PROC_VRD_VCCIN_CPU0
J 0
(4075 1575);
DISPLAY 1.446809 (4075 1575);
PAINT MONO (4075 1575);
DISPLAY INVISIBLE (4075 1575);
FORCEPROP 2 LAST ROOM VDDQ_DEF_PWR_VR
J 0
(3900 1575);
DISPLAY 1.936170 (3900 1575);
PAINT ORANGE (3900 1575);
DISPLAY INVISIBLE (3900 1575);
FORCEPROP 1 LAST BODY_TYPE PLUMBING
J 0
(4405 1457);
DISPLAY 0.340426 (4405 1457);
PAINT GREEN (4405 1457);
DISPLAY INVISIBLE (4405 1457);
FORCEPROP 1 LAST HDL_POWER GND
J 0
(4450 1650);
DISPLAY 1.723404 (4450 1650);
PAINT GREEN (4450 1650);
DISPLAY INVISIBLE (4450 1650);
FORCEADD GND..1
(2325 -750);
FORCEPROP 3 LASTPIN (2325 -700) SIG_NAME GND\g
J 0
(2335 -690);
DISPLAY 0.659574 (2335 -690);
PAINT MONO (2335 -690);
DISPLAY INVISIBLE (2335 -690);
FORCEPROP 1 LAST HDL_POWER GND
J 0
(2325 -600);
DISPLAY 1.723404 (2325 -600);
PAINT GREEN (2325 -600);
DISPLAY INVISIBLE (2325 -600);
FORCEPROP 1 LAST BODY_TYPE PLUMBING
J 0
(2280 -793);
DISPLAY 0.340426 (2280 -793);
PAINT GREEN (2280 -793);
DISPLAY INVISIBLE (2280 -793);
FORCEPROP 2 LAST ROOM VDDQ_DEF_PWR_VR
J 0
(1775 -675);
DISPLAY 1.936170 (1775 -675);
PAINT ORANGE (1775 -675);
DISPLAY INVISIBLE (1775 -675);
FORCEPROP 2 LAST BOM_COST PROC_VRD_VCCIN_CPU0
J 0
(1950 -675);
DISPLAY 1.446809 (1950 -675);
PAINT MONO (1950 -675);
DISPLAY INVISIBLE (1950 -675);
FORCEPROP 1 LAST SIZE 1B
J 0
(2400 -800);
DISPLAY 1.723404 (2400 -800);
PAINT GREEN (2400 -800);
DISPLAY INVISIBLE (2400 -800);
FORCEPROP 1 LAST PATH I70
J 0
(2400 -750);
DISPLAY 1.170213 (2400 -750);
PAINT AQUA (2400 -750);
DISPLAY INVISIBLE (2400 -750);
FORCEPROP 1 LAST VOLTAGE 0
J 0
(2325 -750);
PAINT SKYBLUE (2325 -750);
DISPLAY INVISIBLE (2325 -750);
FORCEPROP 2 LAST CDS_LIB mstr_symbols
J 0
(2325 -750);
PAINT ORANGE (2325 -750);
DISPLAY INVISIBLE (2325 -750);
FORCEADD CAP..1
(-100 175);
FORCEPROP 1 LAST PACK_TYPE 0402
J 0
(-50 -25);
DISPLAY 0.617021 (-50 -25);
PAINT SKYBLUE (-50 -25);
FORCEPROP 0 LAST BOM_SS NOPOP
J 0
(-50 -75);
DISPLAY 0.638298 (-50 -75);
PAINT BROWN (-50 -75);
DISPLAY BOTH (-50 -75);
FORCEPROP 1 LASTPIN (-100 75) $PN 2
J 0
(-90 55);
DISPLAY 0.617021 (-90 55);
PAINT ORANGE (-90 55);
FORCEPROP 1 LAST TOLERANCE 10%
J 0
(-50 125);
DISPLAY 0.617021 (-50 125);
PAINT SKYBLUE (-50 125);
FORCEPROP 1 LAST VOLTAGE 16V
J 0
(-50 175);
DISPLAY 0.617021 (-50 175);
PAINT SKYBLUE (-50 175);
FORCEPROP 1 LASTPIN (-100 275) $PN 1
J 0
(-90 255);
DISPLAY 0.617021 (-90 255);
PAINT ORANGE (-90 255);
FORCEPROP 1 LAST VALUE 0.22UF
J 0
(-50 225);
DISPLAY 0.617021 (-50 225);
PAINT SKYBLUE (-50 225);
FORCEPROP 1 LAST LOCATION C7A25
J 0
(-50 275);
DISPLAY 0.617021 (-50 275);
PAINT AQUA (-50 275);
FORCEPROP 1 LAST PART_NUMBER A36096-155
J 0
(-50 25);
DISPLAY 0.617021 (-50 25);
PAINT BLUE (-50 25);
FORCEPROP 1 LAST MATERIAL X7R
J 0
(-50 75);
DISPLAY 0.617021 (-50 75);
PAINT SKYBLUE (-50 75);
FORCEPROP 2 LAST CDS_LIB mstr_discrete
J 0
(-100 175);
PAINT ORANGE (-100 175);
DISPLAY INVISIBLE (-100 175);
FORCEPROP 2 LAST ROOM VDDQ_DEF_PWR_VR
J 0
(-50 325);
DISPLAY 1.361702 (-50 325);
PAINT ORANGE (-50 325);
DISPLAY INVISIBLE (-50 325);
FORCEPROP 1 LAST PATH I72
J 0
(-50 325);
DISPLAY 1.319149 (-50 325);
PAINT WHITE (-50 325);
DISPLAY INVISIBLE (-50 325);
FORCEPROP 2 LAST CDS_LOCATION C7A25
J 0
(-50 275);
DISPLAY 0.617021 (-50 275);
PAINT AQUA (-50 275);
DISPLAY INVISIBLE (-50 275);
FORCEPROP 2 LAST SEC 1
J 0
(-50 400);
DISPLAY 0.680851 (-50 400);
PAINT MONO (-50 400);
DISPLAY INVISIBLE (-50 400);
FORCEPROP 2 LAST SEC_TYPE 0402
J 0
(-50 400);
DISPLAY 1.021277 (-50 400);
PAINT ORANGE (-50 400);
DISPLAY INVISIBLE (-50 400);
FORCEADD CAP..1
R 2
(-800 -525);
FORCEPROP 1 LASTPIN (-800 -625) $PN 2
J 2
(-810 -645);
DISPLAY 0.617021 (-810 -645);
PAINT ORANGE (-810 -645);
FORCEPROP 1 LAST PART_NUMBER A36096-104
J 2
(-850 -675);
DISPLAY 0.617021 (-850 -675);
PAINT BLUE (-850 -675);
FORCEPROP 1 LAST MATERIAL X7R
J 2
(-850 -625);
DISPLAY 0.617021 (-850 -625);
PAINT SKYBLUE (-850 -625);
FORCEPROP 1 LAST PACK_TYPE 0402
J 2
(-850 -725);
DISPLAY 0.617021 (-850 -725);
PAINT SKYBLUE (-850 -725);
FORCEPROP 1 LASTPIN (-800 -425) $PN 1
J 2
(-810 -445);
DISPLAY 0.617021 (-810 -445);
PAINT ORANGE (-810 -445);
FORCEPROP 1 LAST VOLTAGE 16V
J 2
(-850 -525);
DISPLAY 0.617021 (-850 -525);
PAINT SKYBLUE (-850 -525);
FORCEPROP 1 LAST TOLERANCE 10%
J 2
(-850 -575);
DISPLAY 0.617021 (-850 -575);
PAINT SKYBLUE (-850 -575);
FORCEPROP 1 LAST LOCATION C7A22
J 2
(-850 -425);
DISPLAY 0.617021 (-850 -425);
PAINT AQUA (-850 -425);
FORCEPROP 1 LAST VALUE 0.220UF
J 2
(-850 -475);
DISPLAY 0.617021 (-850 -475);
PAINT SKYBLUE (-850 -475);
FORCEPROP 0 LAST BOM_SS NOPOP
J 0
(-725 -525);
DISPLAY 0.638298 (-725 -525);
PAINT BROWN (-725 -525);
DISPLAY BOTH (-725 -525);
FORCEPROP 2 LAST SEC_TYPE 0402
J 0
(-850 -325);
DISPLAY 1.021277 (-850 -325);
PAINT ORANGE (-850 -325);
DISPLAY INVISIBLE (-850 -325);
FORCEPROP 2 LAST SEC 1
J 0
(-850 -325);
PAINT MONO (-850 -325);
DISPLAY INVISIBLE (-850 -325);
FORCEPROP 2 LAST CDS_LIB mstr_discrete
J 0
(-800 -525);
PAINT ORANGE (-800 -525);
DISPLAY INVISIBLE (-800 -525);
FORCEPROP 0 LAST SPOF TRUE
J 0
(-850 -325);
DISPLAY 1.021277 (-850 -325);
PAINT ORANGE (-850 -325);
DISPLAY INVISIBLE (-850 -325);
FORCEPROP 2 LAST CDS_LOCATION C7A22
J 2
(-850 -425);
DISPLAY 0.617021 (-850 -425);
PAINT AQUA (-850 -425);
DISPLAY INVISIBLE (-850 -425);
FORCEPROP 1 LAST PATH I75
J 2
(-850 -375);
DISPLAY 0.978723 (-850 -375);
PAINT WHITE (-850 -375);
DISPLAY INVISIBLE (-850 -375);
FORCEPROP 2 LAST ROOM VDDQ_DEF_PWR_VR
J 0
(-850 -375);
DISPLAY 1.361702 (-850 -375);
PAINT ORANGE (-850 -375);
DISPLAY INVISIBLE (-850 -375);
FORCEADD CAP..1
(-925 75);
FORCEPROP 1 LAST VALUE 1.0UF
J 0
(-875 125);
DISPLAY 0.617021 (-875 125);
PAINT SKYBLUE (-875 125);
FORCEPROP 1 LAST VOLTAGE 16V
J 0
(-875 75);
DISPLAY 0.617021 (-875 75);
PAINT SKYBLUE (-875 75);
FORCEPROP 1 LASTPIN (-925 175) $PN 1
J 0
(-915 155);
DISPLAY 0.617021 (-915 155);
PAINT ORANGE (-915 155);
FORCEPROP 1 LASTPIN (-925 -25) $PN 2
J 0
(-915 -45);
DISPLAY 0.617021 (-915 -45);
PAINT ORANGE (-915 -45);
FORCEPROP 1 LAST TOLERANCE 10%
J 0
(-875 25);
DISPLAY 0.617021 (-875 25);
PAINT SKYBLUE (-875 25);
FORCEPROP 1 LAST MATERIAL X6S
J 0
(-875 -25);
DISPLAY 0.617021 (-875 -25);
PAINT SKYBLUE (-875 -25);
FORCEPROP 1 LAST PACK_TYPE 0402
J 0
(-875 -125);
DISPLAY 0.617021 (-875 -125);
PAINT SKYBLUE (-875 -125);
FORCEPROP 1 LAST LOCATION C7A24
J 0
(-875 175);
DISPLAY 0.617021 (-875 175);
PAINT AQUA (-875 175);
FORCEPROP 1 LAST PART_NUMBER D97712-011
J 0
(-875 -75);
DISPLAY 0.617021 (-875 -75);
PAINT BLUE (-875 -75);
FORCEPROP 0 LAST BOM_SS NOPOP
J 0
(-900 250);
DISPLAY 0.638298 (-900 250);
PAINT BROWN (-900 250);
DISPLAY BOTH (-900 250);
FORCEPROP 2 LAST SEC_TYPE 0402
J 0
(-875 300);
DISPLAY 1.021277 (-875 300);
PAINT ORANGE (-875 300);
DISPLAY INVISIBLE (-875 300);
FORCEPROP 2 LAST SEC 1
J 0
(-875 300);
DISPLAY 0.680851 (-875 300);
PAINT MONO (-875 300);
DISPLAY INVISIBLE (-875 300);
FORCEPROP 1 LAST PATH I77
J 0
(-875 225);
DISPLAY 1.319149 (-875 225);
PAINT WHITE (-875 225);
DISPLAY INVISIBLE (-875 225);
FORCEPROP 2 LAST ROOM VDDQ_DEF_PWR_VR
J 0
(-875 225);
DISPLAY 1.361702 (-875 225);
PAINT ORANGE (-875 225);
DISPLAY INVISIBLE (-875 225);
FORCEPROP 2 LAST CDS_LOCATION C7A24
J 0
(-875 175);
DISPLAY 0.617021 (-875 175);
PAINT AQUA (-875 175);
DISPLAY INVISIBLE (-875 175);
FORCEPROP 2 LAST CDS_LIB mstr_discrete
J 0
(-925 75);
PAINT ORANGE (-925 75);
DISPLAY INVISIBLE (-925 75);
FORCEADD CAP_A..1
(-1250 75);
FORCEPROP 1 LASTPIN (-1250 175) $PN 1
J 0
(-1240 155);
DISPLAY 0.617021 (-1240 155);
PAINT ORANGE (-1240 155);
FORCEPROP 1 LAST VALUE 0.1UF
J 0
(-1200 125);
DISPLAY 0.617021 (-1200 125);
PAINT SKYBLUE (-1200 125);
FORCEPROP 1 LASTPIN (-1250 -25) $PN 2
J 0
(-1240 -45);
DISPLAY 0.617021 (-1240 -45);
PAINT ORANGE (-1240 -45);
FORCEPROP 1 LAST VOLTAGE 16V
J 0
(-1200 75);
DISPLAY 0.617021 (-1200 75);
PAINT SKYBLUE (-1200 75);
FORCEPROP 1 LAST PACK_TYPE 0402V
J 0
(-1200 -125);
DISPLAY 0.617021 (-1200 -125);
PAINT SKYBLUE (-1200 -125);
FORCEPROP 1 LAST MATERIAL X7R
J 0
(-1200 -25);
DISPLAY 0.617021 (-1200 -25);
PAINT SKYBLUE (-1200 -25);
FORCEPROP 1 LAST TOLERANCE 10%
J 0
(-1200 25);
DISPLAY 0.617021 (-1200 25);
PAINT SKYBLUE (-1200 25);
FORCEPROP 1 LAST LOCATION C7A20
J 0
(-1200 175);
DISPLAY 0.617021 (-1200 175);
PAINT AQUA (-1200 175);
FORCEPROP 1 LAST PART_NUMBER A36096-030
J 0
(-1200 -75);
DISPLAY 0.617021 (-1200 -75);
PAINT BLUE (-1200 -75);
FORCEPROP 2 LAST CDS_LOCATION C7A20
J 0
(-1200 175);
DISPLAY 0.617021 (-1200 175);
PAINT AQUA (-1200 175);
DISPLAY INVISIBLE (-1200 175);
FORCEPROP 2 LAST CDS_LIB dev_discrete
J 0
(-1250 75);
PAINT ORANGE (-1250 75);
DISPLAY INVISIBLE (-1250 75);
FORCEPROP 1 LAST PATH I78
J 0
(-1200 225);
DISPLAY 0.978723 (-1200 225);
PAINT WHITE (-1200 225);
DISPLAY INVISIBLE (-1200 225);
FORCEPROP 2 LAST ROOM VDDQ_DEF_PWR_VR
J 0
(-1200 225);
DISPLAY 1.361702 (-1200 225);
PAINT ORANGE (-1200 225);
DISPLAY INVISIBLE (-1200 225);
FORCEPROP 2 LAST CDS_SEC 1
J 0
(-1200 225);
PAINT ORANGE (-1200 225);
DISPLAY INVISIBLE (-1200 225);
FORCEPROP 2 LAST SEC_TYPE 0402V
J 0
(-1200 300);
DISPLAY 1.021277 (-1200 300);
PAINT ORANGE (-1200 300);
DISPLAY INVISIBLE (-1200 300);
FORCEPROP 2 LAST SEC 1
J 0
(-1200 300);
DISPLAY 0.680851 (-1200 300);
PAINT MONO (-1200 300);
DISPLAY INVISIBLE (-1200 300);
FORCEADD CAP..1
(-1525 75);
FORCEPROP 1 LAST VALUE 1.0UF
J 0
(-1475 125);
DISPLAY 0.617021 (-1475 125);
PAINT SKYBLUE (-1475 125);
FORCEPROP 1 LASTPIN (-1525 -25) $PN 2
J 0
(-1515 -45);
DISPLAY 0.617021 (-1515 -45);
PAINT ORANGE (-1515 -45);
FORCEPROP 1 LAST MATERIAL X6S
J 0
(-1475 -25);
DISPLAY 0.617021 (-1475 -25);
PAINT SKYBLUE (-1475 -25);
FORCEPROP 1 LAST PACK_TYPE 0402
J 0
(-1475 -125);
DISPLAY 0.617021 (-1475 -125);
PAINT SKYBLUE (-1475 -125);
FORCEPROP 1 LAST TOLERANCE 10%
J 0
(-1475 25);
DISPLAY 0.617021 (-1475 25);
PAINT SKYBLUE (-1475 25);
FORCEPROP 1 LAST VOLTAGE 16V
J 0
(-1475 75);
DISPLAY 0.617021 (-1475 75);
PAINT SKYBLUE (-1475 75);
FORCEPROP 1 LAST PART_NUMBER D97712-011
J 0
(-1475 -75);
DISPLAY 0.617021 (-1475 -75);
PAINT BLUE (-1475 -75);
FORCEPROP 1 LASTPIN (-1525 175) $PN 1
J 0
(-1515 155);
DISPLAY 0.617021 (-1515 155);
PAINT ORANGE (-1515 155);
FORCEPROP 1 LAST LOCATION C7A21
J 0
(-1475 175);
DISPLAY 0.617021 (-1475 175);
PAINT AQUA (-1475 175);
FORCEPROP 2 LAST CDS_LIB mstr_discrete
J 0
(-1525 75);
PAINT ORANGE (-1525 75);
DISPLAY INVISIBLE (-1525 75);
FORCEPROP 2 LAST CDS_LOCATION C7A21
J 0
(-1475 175);
DISPLAY 0.617021 (-1475 175);
PAINT AQUA (-1475 175);
DISPLAY INVISIBLE (-1475 175);
FORCEPROP 2 LAST SEC_TYPE 0402
J 0
(-1475 300);
DISPLAY 1.021277 (-1475 300);
PAINT ORANGE (-1475 300);
DISPLAY INVISIBLE (-1475 300);
FORCEPROP 2 LAST SEC 1
J 0
(-1475 300);
DISPLAY 0.680851 (-1475 300);
PAINT MONO (-1475 300);
DISPLAY INVISIBLE (-1475 300);
FORCEPROP 1 LAST PATH I79
J 0
(-1475 225);
DISPLAY 1.319149 (-1475 225);
PAINT WHITE (-1475 225);
DISPLAY INVISIBLE (-1475 225);
FORCEPROP 2 LAST ROOM VDDQ_DEF_PWR_VR
J 0
(-1475 225);
DISPLAY 1.361702 (-1475 225);
PAINT ORANGE (-1475 225);
DISPLAY INVISIBLE (-1475 225);
FORCEADD CAP..1
(-1750 75);
FORCEPROP 1 LAST PACK_TYPE 0805
J 0
(-1700 -125);
DISPLAY 0.617021 (-1700 -125);
PAINT SKYBLUE (-1700 -125);
FORCEPROP 1 LASTPIN (-1750 175) $PN 1
J 0
(-1740 155);
DISPLAY 0.617021 (-1740 155);
PAINT ORANGE (-1740 155);
FORCEPROP 1 LASTPIN (-1750 -25) $PN 2
J 0
(-1740 -45);
DISPLAY 0.617021 (-1740 -45);
PAINT ORANGE (-1740 -45);
FORCEPROP 1 LAST MATERIAL X6S
J 0
(-1700 -25);
DISPLAY 0.617021 (-1700 -25);
PAINT SKYBLUE (-1700 -25);
FORCEPROP 1 LAST TOLERANCE 10%
J 0
(-1700 25);
DISPLAY 0.617021 (-1700 25);
PAINT SKYBLUE (-1700 25);
FORCEPROP 1 LAST VOLTAGE 16V
J 0
(-1700 75);
DISPLAY 0.617021 (-1700 75);
PAINT SKYBLUE (-1700 75);
FORCEPROP 1 LAST VALUE 10UF
J 0
(-1700 125);
DISPLAY 0.617021 (-1700 125);
PAINT SKYBLUE (-1700 125);
FORCEPROP 1 LAST LOCATION C3L17
J 0
(-1700 175);
DISPLAY 0.617021 (-1700 175);
PAINT AQUA (-1700 175);
FORCEPROP 1 LAST PART_NUMBER C95333-007
J 0
(-1700 -75);
DISPLAY 0.617021 (-1700 -75);
PAINT BLUE (-1700 -75);
FORCEPROP 2 LAST ROOM VDDQ_DEF_PWR_VR
J 0
(-1700 225);
DISPLAY 1.361702 (-1700 225);
PAINT ORANGE (-1700 225);
DISPLAY INVISIBLE (-1700 225);
FORCEPROP 1 LAST PATH I80
J 0
(-1700 225);
DISPLAY 1.319149 (-1700 225);
PAINT WHITE (-1700 225);
DISPLAY INVISIBLE (-1700 225);
FORCEPROP 2 LAST SEC 1
J 0
(-1700 300);
DISPLAY 0.680851 (-1700 300);
PAINT MONO (-1700 300);
DISPLAY INVISIBLE (-1700 300);
FORCEPROP 2 LAST SEC_TYPE 0805
J 0
(-1700 300);
DISPLAY 1.021277 (-1700 300);
PAINT ORANGE (-1700 300);
DISPLAY INVISIBLE (-1700 300);
FORCEPROP 2 LAST CDS_LOCATION C3L17
J 0
(-1700 175);
DISPLAY 0.617021 (-1700 175);
PAINT AQUA (-1700 175);
DISPLAY INVISIBLE (-1700 175);
FORCEPROP 2 LAST CDS_LIB mstr_discrete
J 0
(-1750 75);
PAINT ORANGE (-1750 75);
DISPLAY INVISIBLE (-1750 75);
FORCEADD CAP..1
(-1975 75);
FORCEPROP 1 LAST PART_NUMBER C95333-007
J 0
(-1925 -75);
DISPLAY 0.617021 (-1925 -75);
PAINT BLUE (-1925 -75);
FORCEPROP 1 LAST PACK_TYPE 0805
J 0
(-1925 -125);
DISPLAY 0.617021 (-1925 -125);
PAINT SKYBLUE (-1925 -125);
FORCEPROP 1 LAST VALUE 10UF
J 0
(-1925 125);
DISPLAY 0.617021 (-1925 125);
PAINT SKYBLUE (-1925 125);
FORCEPROP 1 LAST TOLERANCE 10%
J 0
(-1925 25);
DISPLAY 0.617021 (-1925 25);
PAINT SKYBLUE (-1925 25);
FORCEPROP 1 LASTPIN (-1975 175) $PN 1
J 0
(-1965 155);
DISPLAY 0.617021 (-1965 155);
PAINT ORANGE (-1965 155);
FORCEPROP 1 LASTPIN (-1975 -25) $PN 2
J 0
(-1965 -45);
DISPLAY 0.617021 (-1965 -45);
PAINT ORANGE (-1965 -45);
FORCEPROP 1 LAST MATERIAL X6S
J 0
(-1925 -25);
DISPLAY 0.617021 (-1925 -25);
PAINT SKYBLUE (-1925 -25);
FORCEPROP 1 LAST VOLTAGE 16V
J 0
(-1925 75);
DISPLAY 0.617021 (-1925 75);
PAINT SKYBLUE (-1925 75);
FORCEPROP 1 LAST LOCATION C3L16
J 0
(-1925 175);
DISPLAY 0.617021 (-1925 175);
PAINT AQUA (-1925 175);
FORCEPROP 2 LAST CDS_LIB mstr_discrete
J 0
(-1975 75);
PAINT ORANGE (-1975 75);
DISPLAY INVISIBLE (-1975 75);
FORCEPROP 2 LAST CDS_LOCATION C3L16
J 0
(-1925 175);
DISPLAY 0.617021 (-1925 175);
PAINT AQUA (-1925 175);
DISPLAY INVISIBLE (-1925 175);
FORCEPROP 2 LAST SEC_TYPE 0805
J 0
(-1925 300);
DISPLAY 1.021277 (-1925 300);
PAINT ORANGE (-1925 300);
DISPLAY INVISIBLE (-1925 300);
FORCEPROP 2 LAST SEC 1
J 0
(-1925 300);
DISPLAY 0.680851 (-1925 300);
PAINT MONO (-1925 300);
DISPLAY INVISIBLE (-1925 300);
FORCEPROP 1 LAST PATH I81
J 0
(-1925 225);
DISPLAY 1.319149 (-1925 225);
PAINT WHITE (-1925 225);
DISPLAY INVISIBLE (-1925 225);
FORCEPROP 2 LAST ROOM VDDQ_DEF_PWR_VR
J 0
(-1925 225);
DISPLAY 1.361702 (-1925 225);
PAINT ORANGE (-1925 225);
DISPLAY INVISIBLE (-1925 225);
FORCEADD OFFPAGE..1
(525 -225);
FORCEPROP 2 LAST $XR0 218 
J 0
(-147 -225);
DISPLAY 0.638298 (-147 -225);
PAINT MONO (-147 -225);
FORCEPROP 1 LAST COMMENT_BODY TRUE
J 0
(650 -325);
DISPLAY 1.680851 (650 -325);
PAINT GREEN (650 -325);
DISPLAY INVISIBLE (650 -325);
FORCEPROP 1 LAST OFFPAGE TRUE
J 0
(850 -350);
DISPLAY 1.680851 (850 -350);
PAINT GREEN (850 -350);
DISPLAY INVISIBLE (850 -350);
FORCEPROP 2 LAST BOM_COST PROC_VRD_VCCIN_CPU0
J 0
(275 -175);
DISPLAY 1.446809 (275 -175);
PAINT MONO (275 -175);
DISPLAY INVISIBLE (275 -175);
FORCEPROP 2 LAST CDS_LIB mstr_standard
J 0
(525 -225);
PAINT ORANGE (525 -225);
DISPLAY INVISIBLE (525 -225);
FORCEPROP 2 LAST PATH I82
J 0
(580 -150);
DISPLAY 1.361702 (580 -150);
PAINT ORANGE (580 -150);
DISPLAY INVISIBLE (580 -150);
FORCEPROP 2 LAST ROOM VDDQ_DEF_PWR_VR
J 0
(125 -150);
DISPLAY 1.936170 (125 -150);
PAINT ORANGE (125 -150);
DISPLAY INVISIBLE (125 -150);
FORCEADD VCC_CORE..1
(-1975 400);
FORCEPROP 3 LASTPIN (-1975 350) SIG_NAME VR_FET_SW_P12V_STBY_PVDDQ_DEF\g
J 0
(-1965 360);
DISPLAY 0.659574 (-1965 360);
PAINT MONO (-1965 360);
DISPLAY INVISIBLE (-1965 360);
FORCEPROP 1 LAST HDL_POWER VR_FET_SW_P12V_STBY_PVDDQ_DEF
J 1
(-1875 450);
DISPLAY 0.617021 (-1875 450);
PAINT GREEN (-1875 450);
FORCEPROP 2 LAST CDS_LIB mstr_symbols
J 0
(-1975 400);
PAINT ORANGE (-1975 400);
DISPLAY INVISIBLE (-1975 400);
FORCEPROP 1 LAST PATH I83
J 0
(-1925 425);
DISPLAY 1.170213 (-1925 425);
PAINT AQUA (-1925 425);
DISPLAY INVISIBLE (-1925 425);
FORCEADD CAP..1
(-2200 75);
FORCEPROP 1 LAST PART_NUMBER C95333-007
J 0
(-2150 -75);
DISPLAY 0.617021 (-2150 -75);
PAINT BLUE (-2150 -75);
FORCEPROP 1 LAST MATERIAL X6S
J 0
(-2150 -25);
DISPLAY 0.617021 (-2150 -25);
PAINT SKYBLUE (-2150 -25);
FORCEPROP 1 LAST TOLERANCE 10%
J 0
(-2150 25);
DISPLAY 0.617021 (-2150 25);
PAINT SKYBLUE (-2150 25);
FORCEPROP 1 LAST VOLTAGE 16V
J 0
(-2150 75);
DISPLAY 0.617021 (-2150 75);
PAINT SKYBLUE (-2150 75);
FORCEPROP 1 LAST VALUE 10UF
J 0
(-2150 125);
DISPLAY 0.617021 (-2150 125);
PAINT SKYBLUE (-2150 125);
FORCEPROP 1 LASTPIN (-2200 175) $PN 1
J 0
(-2190 155);
DISPLAY 0.617021 (-2190 155);
PAINT ORANGE (-2190 155);
FORCEPROP 1 LASTPIN (-2200 -25) $PN 2
J 0
(-2190 -45);
DISPLAY 0.617021 (-2190 -45);
PAINT ORANGE (-2190 -45);
FORCEPROP 1 LAST PACK_TYPE 0805
J 0
(-2150 -125);
DISPLAY 0.617021 (-2150 -125);
PAINT SKYBLUE (-2150 -125);
FORCEPROP 1 LAST LOCATION C3L15
J 0
(-2150 175);
DISPLAY 0.617021 (-2150 175);
PAINT AQUA (-2150 175);
FORCEPROP 2 LAST CDS_LOCATION C3L15
J 0
(-2150 175);
DISPLAY 0.617021 (-2150 175);
PAINT AQUA (-2150 175);
DISPLAY INVISIBLE (-2150 175);
FORCEPROP 2 LAST CDS_LIB mstr_discrete
J 0
(-2200 75);
PAINT ORANGE (-2200 75);
DISPLAY INVISIBLE (-2200 75);
FORCEPROP 2 LAST ROOM VDDQ_DEF_PWR_VR
J 0
(-2150 225);
DISPLAY 1.361702 (-2150 225);
PAINT ORANGE (-2150 225);
DISPLAY INVISIBLE (-2150 225);
FORCEPROP 1 LAST PATH I84
J 0
(-2150 225);
DISPLAY 1.319149 (-2150 225);
PAINT WHITE (-2150 225);
DISPLAY INVISIBLE (-2150 225);
FORCEPROP 2 LAST SEC_TYPE 0805
J 0
(-2150 300);
DISPLAY 1.021277 (-2150 300);
PAINT ORANGE (-2150 300);
DISPLAY INVISIBLE (-2150 300);
FORCEPROP 2 LAST SEC 1
J 0
(-2150 300);
DISPLAY 0.680851 (-2150 300);
PAINT MONO (-2150 300);
DISPLAY INVISIBLE (-2150 300);
FORCEADD GND..1
(-2200 -225);
FORCEPROP 3 LASTPIN (-2200 -175) SIG_NAME GND\g
J 0
(-2190 -165);
DISPLAY 0.659574 (-2190 -165);
PAINT MONO (-2190 -165);
DISPLAY INVISIBLE (-2190 -165);
FORCEPROP 2 LAST ROOM VDDQ_DEF_PWR_VR
J 0
(-2750 -150);
DISPLAY 1.936170 (-2750 -150);
PAINT ORANGE (-2750 -150);
DISPLAY INVISIBLE (-2750 -150);
FORCEPROP 2 LAST BOM_COST PROC_VRD_VCCIN_CPU0
J 0
(-2575 -150);
DISPLAY 1.446809 (-2575 -150);
PAINT MONO (-2575 -150);
DISPLAY INVISIBLE (-2575 -150);
FORCEPROP 1 LAST VOLTAGE 0
J 0
(-2200 -225);
PAINT SKYBLUE (-2200 -225);
DISPLAY INVISIBLE (-2200 -225);
FORCEPROP 1 LAST SIZE 1B
J 0
(-2125 -275);
DISPLAY 1.723404 (-2125 -275);
PAINT GREEN (-2125 -275);
DISPLAY INVISIBLE (-2125 -275);
FORCEPROP 2 LAST CDS_LIB mstr_symbols
J 0
(-2200 -225);
PAINT ORANGE (-2200 -225);
DISPLAY INVISIBLE (-2200 -225);
FORCEPROP 1 LAST PATH I85
J 0
(-2125 -225);
DISPLAY 1.170213 (-2125 -225);
PAINT AQUA (-2125 -225);
DISPLAY INVISIBLE (-2125 -225);
FORCEPROP 1 LAST BODY_TYPE PLUMBING
J 0
(-2245 -268);
DISPLAY 0.340426 (-2245 -268);
PAINT GREEN (-2245 -268);
DISPLAY INVISIBLE (-2245 -268);
FORCEPROP 1 LAST HDL_POWER GND
J 0
(-2200 -75);
DISPLAY 1.723404 (-2200 -75);
PAINT GREEN (-2200 -75);
DISPLAY INVISIBLE (-2200 -75);
FORCEADD VCC_CORE..1
(-1800 2675);
FORCEPROP 3 LASTPIN (-1800 2625) SIG_NAME VR_FET_SW_P12V_STBY_PVDDQ_DEF\g
J 0
(-1790 2635);
DISPLAY 0.659574 (-1790 2635);
PAINT MONO (-1790 2635);
DISPLAY INVISIBLE (-1790 2635);
FORCEPROP 1 LAST HDL_POWER VR_FET_SW_P12V_STBY_PVDDQ_DEF
J 1
(-1700 2725);
DISPLAY 0.617021 (-1700 2725);
PAINT GREEN (-1700 2725);
FORCEPROP 2 LAST CDS_LIB mstr_symbols
J 0
(-1800 2675);
PAINT ORANGE (-1800 2675);
DISPLAY INVISIBLE (-1800 2675);
FORCEPROP 1 LAST PATH I86
J 0
(-1750 2700);
DISPLAY 1.170213 (-1750 2700);
PAINT AQUA (-1750 2700);
DISPLAY INVISIBLE (-1750 2700);
FORCEADD CAP..1
(4450 1675);
FORCEPROP 1 LASTPIN (4450 1775) $PN 1
J 0
(4460 1755);
DISPLAY 0.787234 (4460 1755);
PAINT ORANGE (4460 1755);
FORCEPROP 1 LAST PACK_TYPE 0805LF
J 0
(4500 1475);
DISPLAY 0.617021 (4500 1475);
PAINT SKYBLUE (4500 1475);
FORCEPROP 1 LAST LOCATION C6A1
J 0
(4500 1775);
DISPLAY 0.617021 (4500 1775);
PAINT AQUA (4500 1775);
FORCEPROP 1 LAST VOLTAGE 4V
J 0
(4500 1675);
DISPLAY 0.723404 (4500 1675);
PAINT SKYBLUE (4500 1675);
FORCEPROP 1 LAST VALUE 22UF
J 0
(4500 1725);
DISPLAY 0.617021 (4500 1725);
PAINT SKYBLUE (4500 1725);
FORCEPROP 0 LAST GROUP PWR_MLCC_CAP
J 0
(4506 1437);
DISPLAY 0.638298 (4506 1437);
PAINT BROWN (4506 1437);
DISPLAY BOTH (4506 1437);
FORCEPROP 1 LAST PART_NUMBER C95333-002
J 0
(4500 1525);
DISPLAY 0.617021 (4500 1525);
PAINT BLUE (4500 1525);
FORCEPROP 1 LASTPIN (4450 1575) $PN 2
J 0
(4460 1555);
DISPLAY 0.787234 (4460 1555);
PAINT ORANGE (4460 1555);
FORCEPROP 1 LAST MATERIAL X6S
J 0
(4500 1575);
DISPLAY 0.617021 (4500 1575);
PAINT SKYBLUE (4500 1575);
FORCEPROP 1 LAST TOLERANCE 20%
J 0
(4500 1625);
DISPLAY 0.617021 (4500 1625);
PAINT SKYBLUE (4500 1625);
FORCEPROP 2 LAST SEC_TYPE 0805LF
J 0
(4500 1875);
DISPLAY 1.021277 (4500 1875);
PAINT ORANGE (4500 1875);
DISPLAY INVISIBLE (4500 1875);
FORCEPROP 2 LAST SEC 1
J 0
(4505 1875);
DISPLAY 0.680851 (4505 1875);
PAINT MONO (4505 1875);
DISPLAY INVISIBLE (4505 1875);
FORCEPROP 2 LAST ROOM VDDQ_DEF_PWR_VR
J 0
(4500 1825);
DISPLAY 1.446809 (4500 1825);
PAINT MONO (4500 1825);
DISPLAY INVISIBLE (4500 1825);
FORCEPROP 1 LAST PATH I87
J 0
(4500 1825);
DISPLAY 0.978723 (4500 1825);
PAINT WHITE (4500 1825);
DISPLAY INVISIBLE (4500 1825);
FORCEPROP 2 LAST CDS_LOCATION C6A1
J 0
(4500 1775);
DISPLAY 0.617021 (4500 1775);
PAINT AQUA (4500 1775);
DISPLAY INVISIBLE (4500 1775);
FORCEPROP 2 LAST BOM_COST PROC_VRD_VCCIN_CPU0
J 0
(4500 1825);
DISPLAY 1.446809 (4500 1825);
PAINT MONO (4500 1825);
DISPLAY INVISIBLE (4500 1825);
FORCEPROP 2 LAST CDS_LIB mstr_discrete
J 0
(4450 1675);
PAINT ORANGE (4450 1675);
DISPLAY INVISIBLE (4450 1675);
FORCEADD P5V_STBY..1
(300 825);
FORCEPROP 3 LASTPIN (300 775) SIG_NAME P5V_STBY\g
J 0
(310 785);
DISPLAY 0.659574 (310 785);
PAINT MONO (310 785);
DISPLAY INVISIBLE (310 785);
FORCEPROP 1 LAST SIZE 1B
J 0
(345 847);
DISPLAY 0.340426 (345 847);
PAINT GREEN (345 847);
DISPLAY INVISIBLE (345 847);
FORCEPROP 1 LAST PATH I89
J 0
(345 827);
DISPLAY 0.340426 (345 827);
PAINT GREEN (345 827);
DISPLAY INVISIBLE (345 827);
FORCEPROP 2 LAST CDS_LIB mstr_symbols
J 0
(300 825);
PAINT ORANGE (300 825);
DISPLAY INVISIBLE (300 825);
FORCEPROP 1 LAST VOLTAGE 5.0V
J 0
(255 782);
DISPLAY 0.340426 (255 782);
PAINT SKYBLUE (255 782);
DISPLAY INVISIBLE (255 782);
FORCEPROP 1 LAST BODY_TYPE PLUMBING
J 0
(255 782);
DISPLAY 0.340426 (255 782);
PAINT GREEN (255 782);
DISPLAY INVISIBLE (255 782);
FORCEPROP 1 LAST HDL_POWER P5V_STBY
J 0
(0 700);
DISPLAY 0.872340 (0 700);
PAINT ORANGE (0 700);
DISPLAY INVISIBLE (0 700);
FORCEADD DNS..2
(4580 2295);
PAINT RED (4580 2295);
FORCEPROP 1 LAST COMMENT_BODY TRUE
R 1
J 0
(4655 2070);
DISPLAY 0.872340 (4655 2070);
PAINT GREEN (4655 2070);
DISPLAY INVISIBLE (4655 2070);
FORCEPROP 2 LAST CDS_LIB mstr_misc
J 0
(4580 2295);
PAINT ORANGE (4580 2295);
DISPLAY INVISIBLE (4580 2295);
FORCEADD DNS..2
(4580 20);
PAINT RED (4580 20);
FORCEPROP 2 LAST CDS_LIB mstr_misc
J 0
(4580 20);
PAINT ORANGE (4580 20);
DISPLAY INVISIBLE (4580 20);
FORCEPROP 1 LAST COMMENT_BODY TRUE
R 1
J 0
(4655 -205);
DISPLAY 0.872340 (4655 -205);
PAINT GREEN (4655 -205);
DISPLAY INVISIBLE (4655 -205);
FORCEADD INTEL_CORP_BPAGE..1
(5525 -1700);
FORCEPROP 1 LAST CDS_CON_LAST_MODIFIED Fri Jun 16 17:49:19 2017
J 0
(4100 -1375);
DISPLAY 1.936170 (4100 -1375);
PAINT GREEN (4100 -1375);
DISPLAY INVISIBLE (4100 -1375);
FORCEPROP 2 LAST CUSTOM_TXT_CDS <XR_PAGE_TITLE>
J 0
(-2365 3550);
DISPLAY 0.638298 (-2365 3550);
PAINT PINK (-2365 3550);
DISPLAY INVISIBLE (-2365 3550);
FORCEPROP 2 LAST CUSTOM_TXT_CDS <CON_LAST_MODIFIED>
J 0
(1525 -1600);
PAINT ORANGE (1525 -1600);
FORCEPROP 2 LAST CUSTOM_TXT_CDS <CURRENT_DESIGN_SHEET> OF <TOTAL_DESIGN_SHEETS>
J 0
(5025 -1675);
PAINT ORANGE (5025 -1675);
FORCEPROP 1 LAST SCH_TITLE VDDQ DEF_VR (2 OF 3)
J 0
(-2425 -1650);
DISPLAY 1.212766 (-2425 -1650);
PAINT ORANGE (-2425 -1650);
FORCEPROP 1 LAST COMMENT_BODY TRUE
J 0
(5537 -1688);
DISPLAY 0.893617 (5537 -1688);
PAINT GREEN (5537 -1688);
DISPLAY INVISIBLE (5537 -1688);
FORCEPROP 2 LAST CDS_LIB mstr_symbols
J 0
(5525 -1700);
DISPLAY 1.936170 (5525 -1700);
PAINT ORANGE (5525 -1700);
DISPLAY INVISIBLE (5525 -1700);
FORCEPROP 2 LAST PAGE_BORDER TRUE
J 0
(-2365 3550);
DISPLAY 1.255319 (-2365 3550);
PAINT PINK (-2365 3550);
DISPLAY INVISIBLE (-2365 3550);
FORCEPROP 2 LAST ROOM CPU0_CORE_VR
J 0
(-2575 3400);
DISPLAY 1.936170 (-2575 3400);
PAINT ORANGE (-2575 3400);
DISPLAY INVISIBLE (-2575 3400);
FORCEPROP 2 LAST CDS_XR_PAGE_TITLE CR-219 : @BASEBOARD_FAB2_LIB.BASEBOARD_FAB2(SCH_1):PAGE219
J 0
(-2365 3550);
DISPLAY 0.638298 (-2365 3550);
PAINT PINK (-2365 3550);
DISPLAY INVISIBLE (-2365 3550);
WIRE 16 -1 (4450 1825)(4450 1875);
WIRE 16 -1 (4350 1825)(4450 1825);
WIRE 16 -1 (4450 1775)(4450 1825);
WIRE 16 -1 (4350 1100)(4350 1825);
WIRE 16 -1 (4000 1825)(4350 1825);
WIRE 16 -1 (1150 1100)(4350 1100);
WIRE 16 -1 (1150 2275)(1150 1100);
WIRE 16 -1 (1250 2275)(1150 2275);
WIRE 16 -1 (4575 2175)(4575 2200);
WIRE 16 -1 (4575 -125)(4575 -75);
WIRE 16 -1 (225 3000)(225 3100);
WIRE 16 -1 (225 2475)(225 3000);
WIRE 16 -1 (-125 3000)(225 3000);
WIRE 16 -1 (-125 3000)(-450 3000);
WIRE 16 -1 (-125 2525)(-125 3000);
WIRE 16 -1 (1150 2475)(225 2475);
WIRE 16 -1 (1150 2375)(1150 2475);
WIRE 16 -1 (1250 2475)(1150 2475);
WIRE 16 -1 (-450 2425)(-450 3000);
WIRE 16 -1 (-450 3000)(-625 3000);
WIRE 16 -1 (1250 2375)(1150 2375);
WIRE 16 -1 (1075 -725)(1075 -850);
WIRE 16 -1 (1025 1525)(1025 1425);
WIRE 16 -1 (3075 -200)(3075 -250);
WIRE 16 -1 (2875 -1050)(2875 -1075);
WIRE 16 -1 (2900 2025)(2900 1975);
WIRE 16 -1 (2300 1550)(2300 1575);
WIRE 16 -1 (2300 1575)(2300 1625);
WIRE 16 -1 (2300 1575)(2250 1575);
WIRE 16 -1 (2300 1625)(2300 1675);
WIRE 16 -1 (2300 1625)(2250 1625);
WIRE 16 -1 (2300 1675)(2300 1725);
WIRE 16 -1 (2300 1675)(2250 1675);
WIRE 16 -1 (2250 1725)(2300 1725);
WIRE 16 -1 (-2225 2050)(-2225 2100);
WIRE 16 -1 (-2225 2100)(-2000 2100);
WIRE 16 -1 (-2225 2325)(-2225 2100);
WIRE 16 -1 (-1775 2100)(-2000 2100);
WIRE 16 -1 (-2000 2325)(-2000 2100);
WIRE 16 -1 (-1475 2100)(-1775 2100);
WIRE 16 -1 (-1775 2325)(-1775 2100);
WIRE 16 -1 (-1175 2100)(-1475 2100);
WIRE 16 -1 (-1475 2325)(-1475 2100);
WIRE 16 -1 (-875 2100)(-1175 2100);
WIRE 16 -1 (-1175 2325)(-1175 2100);
WIRE 16 -1 (-450 2100)(-875 2100);
WIRE 16 -1 (-875 2325)(-875 2100);
WIRE 16 -1 (-125 2100)(-450 2100);
WIRE 16 -1 (-450 2275)(-450 2100);
WIRE 16 -1 (-125 2325)(-125 2100);
WIRE 16 -1 (4500 -425)(4500 -375);
WIRE 16 -1 (4400 -425)(4500 -425);
WIRE 16 -1 (4500 -475)(4500 -425);
WIRE 16 -1 (4400 -1225)(4400 -425);
WIRE 16 -1 (4000 -425)(4400 -425);
WIRE 16 -1 (1175 -1225)(4400 -1225);
WIRE 16 -1 (1175 25)(1175 -1225);
WIRE 16 -1 (1275 25)(1175 25);
WIRE 16 -1 (4500 -700)(4500 -675);
WIRE 16 -1 (4450 1550)(4450 1575);
WIRE 16 -1 (2325 -700)(2325 -675);
WIRE 16 -1 (2325 -675)(2325 -625);
WIRE 16 -1 (2325 -675)(2275 -675);
WIRE 16 -1 (2325 -625)(2325 -575);
WIRE 16 -1 (2325 -625)(2275 -625);
WIRE 16 -1 (2325 -575)(2325 -525);
WIRE 16 -1 (2325 -575)(2275 -575);
WIRE 16 -1 (2275 -525)(2325 -525);
WIRE 16 -1 (-1975 350)(-1975 325);
WIRE 16 -1 (-1750 325)(-1975 325);
WIRE 16 -1 (-2200 325)(-1975 325);
WIRE 16 -1 (-1975 175)(-1975 325);
WIRE 16 -1 (-2200 175)(-2200 325);
WIRE 16 -1 (-1750 325)(-1525 325);
WIRE 16 -1 (-1750 175)(-1750 325);
WIRE 16 -1 (-1250 325)(-1525 325);
WIRE 16 -1 (-1525 175)(-1525 325);
WIRE 16 -1 (925 325)(-1250 325);
WIRE 16 -1 (-1250 175)(-1250 325);
WIRE 16 -1 (925 375)(925 325);
WIRE 16 -1 (1275 325)(925 325);
WIRE 16 -1 (1275 375)(925 375);
WIRE 16 -1 (-2200 -175)(-2200 -150);
WIRE 16 -1 (-2200 -150)(-1975 -150);
WIRE 16 -1 (-2200 -25)(-2200 -150);
WIRE 16 -1 (-1750 -150)(-1975 -150);
WIRE 16 -1 (-1975 -25)(-1975 -150);
WIRE 16 -1 (-1750 -150)(-1525 -150);
WIRE 16 -1 (-1750 -25)(-1750 -150);
WIRE 16 -1 (-1250 -150)(-1525 -150);
WIRE 16 -1 (-1525 -25)(-1525 -150);
WIRE 16 -1 (-925 -150)(-1250 -150);
WIRE 16 -1 (-1250 -25)(-1250 -150);
WIRE 16 -1 (-925 -150)(-525 -150);
WIRE 16 -1 (-925 -25)(-925 -150);
WIRE 16 -1 (-100 -150)(-525 -150);
WIRE 16 -1 (-525 25)(-525 -150);
WIRE 16 -1 (-100 75)(-100 -150);
WIRE 16 -1 (-1800 2625)(-1800 2575);
WIRE 16 -1 (-1800 2575)(-1775 2575);
WIRE 16 -1 (-1800 2575)(-2000 2575);
WIRE 16 -1 (-2225 2575)(-2000 2575);
WIRE 16 -1 (-2000 2525)(-2000 2575);
WIRE 16 -1 (-1475 2575)(-1775 2575);
WIRE 16 -1 (-1775 2525)(-1775 2575);
WIRE 16 -1 (-1175 2575)(-1475 2575);
WIRE 16 -1 (-1475 2525)(-1475 2575);
WIRE 16 -1 (-2225 2525)(-2225 2575);
WIRE 16 -1 (1100 2575)(-1175 2575);
WIRE 16 -1 (-1175 2525)(-1175 2575);
WIRE 16 -1 (1100 2625)(1100 2575);
WIRE 16 -1 (1250 2575)(1100 2575);
WIRE 16 -1 (1250 2625)(1100 2625);
WIRE 16 -1 (300 700)(300 775);
WIRE 16 -1 (300 700)(300 225);
WIRE 16 -1 (300 700)(-100 700);
WIRE 16 -1 (-100 700)(-525 700);
WIRE 16 -1 (-100 275)(-100 700);
WIRE 16 -1 (1150 225)(300 225);
WIRE 16 -1 (1150 125)(1150 225);
WIRE 16 -1 (1275 225)(1150 225);
WIRE 16 -1 (-525 175)(-525 700);
WIRE 16 -1 (-675 700)(-525 700);
WIRE 16 -1 (1275 125)(1150 125);
WIRE 3 682 (-2300 -250)(-1000 -250);
WIRE 3 682 (-2300 500)(-2300 -250);
WIRE 3 682 (-1000 -250)(-1000 500);
WIRE 3 682 (-1000 500)(-2300 500);
WIRE 16 2175 (-650 -125)(125 -125);
WIRE 16 2175 (125 300)(125 -125);
WIRE 16 2175 (-650 300)(-650 -125);
WIRE 16 2175 (-650 300)(125 300);
WIRE 16 2175 (-1125 -775)(-125 -775);
WIRE 16 2175 (-125 -275)(-125 -775);
WIRE 16 2175 (-1125 -275)(-1125 -775);
WIRE 16 2175 (-1125 -275)(-125 -275);
WIRE 16 -1 (-800 -350)(-800 -425);
WIRE 16 -1 (75 -350)(-800 -350);
FORCEPROP 2 LAST SIG_NAME VR_PVDDQ_DEF_PH2_BOOT
J 0
(-765 -340);
DISPLAY 0.617021 (-765 -340);
PAINT ORANGE (-765 -340);
FORCEPROP 2 LASTPROP $XRERR UNIQUE?
J 0
(-1005 -340);
DISPLAY 0.638298 (-1005 -340);
PAINT MONO (-1005 -340);
DISPLAY INVISIBLE (-1005 -340);
WIRE 16 -1 (-925 700)(-875 700);
WIRE 16 -1 (-925 175)(-925 425);
WIRE 16 -1 (-925 425)(-925 700);
WIRE 16 -1 (1275 425)(-925 425);
FORCEPROP 2 LAST SIG_NAME VR_PVDDQ_DEF_PH2_VCIN
J 0
(-865 435);
DISPLAY 0.617021 (-865 435);
PAINT ORANGE (-865 435);
FORCEPROP 2 LASTPROP $XRERR UNIQUE?
J 0
(-1105 435);
DISPLAY 0.638298 (-1105 435);
PAINT MONO (-1105 435);
DISPLAY INVISIBLE (-1105 435);
WIRE 3 682 (-475 -75)(-575 -75);
WIRE 3 682 (-475 225)(-475 -75);
WIRE 3 682 (-575 -75)(-575 225);
WIRE 3 682 (-575 225)(-475 225);
WIRE 3 682 (-2350 900)(-2350 -1350);
WIRE 3 682 (5300 900)(-2350 900);
WIRE 3 682 (-2350 -1350)(5300 -1350);
WIRE 3 682 (5300 -1350)(5300 900);
WIRE 3 2175 (-950 800)(-600 800);
WIRE 3 2175 (-600 800)(-600 550);
WIRE 3 2175 (-950 800)(-950 550);
WIRE 3 2175 (-950 550)(-600 550);
WIRE 16 -1 (575 -225)(1275 -225);
FORCEPROP 2 LAST SIG_NAME VR_PVDDQ_DEF_PWM2
J 0
(562 -215);
DISPLAY 0.617021 (562 -215);
PAINT ORANGE (562 -215);
WIRE 16 -1 (4575 2400)(4575 2475);
WIRE 16 -1 (2250 2475)(4575 2475);
FORCEPROP 0 LAST VOLTAGE 3.6
J 0
(2325 2550);
DISPLAY 1.021277 (2325 2550);
PAINT SKYBLUE (2325 2550);
DISPLAY INVISIBLE (2325 2550);
FORCEPROP 2 LAST SIG_NAME VR_PVDDQ_DEF_PH1_OCSET
J 0
(2382 2491);
DISPLAY 0.617021 (2382 2491);
PAINT ORANGE (2382 2491);
FORCEPROP 2 LASTPROP $XRERR UNIQUE?
J 0
(2142 2491);
DISPLAY 0.638298 (2142 2491);
PAINT MONO (2142 2491);
DISPLAY INVISIBLE (2142 2491);
WIRE 16 -1 (-875 3000)(-825 3000);
WIRE 16 -1 (-875 2675)(-875 3000);
WIRE 16 -1 (1250 2675)(-875 2675);
WIRE 16 -1 (-875 2525)(-875 2675);
FORCEPROP 2 LAST SIG_NAME VR_PVDDQ_DEF_PH1_VCIN
J 0
(-815 2685);
DISPLAY 0.617021 (-815 2685);
PAINT ORANGE (-815 2685);
FORCEPROP 2 LASTPROP $XRERR UNIQUE?
J 0
(-1055 2685);
DISPLAY 0.638298 (-1055 2685);
PAINT MONO (-1055 2685);
DISPLAY INVISIBLE (-1055 2685);
WIRE 3 2175 (0 -250)(0 -625);
WIRE 3 2175 (0 -625)(325 -625);
WIRE 3 2175 (0 -250)(325 -250);
WIRE 3 2175 (325 -250)(325 -625);
WIRE 16 -1 (875 -350)(275 -350);
FORCEPROP 2 LAST SIG_NAME VR_PVDDQ_DEF_PH2_BOOT_R
J 0
(435 -340);
DISPLAY 0.617021 (435 -340);
PAINT ORANGE (435 -340);
FORCEPROP 2 LASTPROP $XRERR UNIQUE?
J 0
(195 -340);
DISPLAY 0.638298 (195 -340);
PAINT MONO (195 -340);
DISPLAY INVISIBLE (195 -340);
WIRE 16 -1 (875 -425)(875 -350);
WIRE 16 -1 (875 -425)(1275 -425);
WIRE 16 -1 (1075 750)(3425 750);
FORCEPROP 2 LAST SIG_NAME VR_PVDDQ_DEF_AIREF2
J 0
(2998 756);
DISPLAY 0.617021 (2998 756);
PAINT ORANGE (2998 756);
WIRE 16 -1 (1075 -525)(1075 -325);
WIRE 16 -1 (1275 -325)(1075 -325);
WIRE 16 -1 (1075 -325)(1075 750);
WIRE 16 -1 (3075 0)(3075 75);
WIRE 16 -1 (3075 75)(3675 75);
WIRE 16 -1 (2275 75)(2275 -75);
WIRE 16 -1 (2275 75)(3075 75);
FORCEPROP 2 LAST SIG_NAME A_TSENSE_PVDDQ_DEF
J 0
(2287 85);
DISPLAY 0.617021 (2287 85);
PAINT ORANGE (2287 85);
WIRE 3 2175 (2950 -350)(3450 -350);
WIRE 3 2175 (3450 125)(3450 -350);
WIRE 3 2175 (2950 125)(2950 -350);
WIRE 3 2175 (2950 125)(3450 125);
WIRE 16 -1 (2875 -500)(2875 -425);
WIRE 16 -1 (2875 -425)(3700 -425);
WIRE 16 -1 (2275 -425)(2875 -425);
FORCEPROP 2 LAST SIG_NAME VR_PVDDQ_DEF_PH2_SW
J 0
(2435 -415);
DISPLAY 0.617021 (2435 -415);
PAINT ORANGE (2435 -415);
FORCEPROP 2 LASTPROP $XRERR UNIQUE?
J 0
(2195 -415);
DISPLAY 0.638298 (2195 -415);
PAINT MONO (2195 -415);
DISPLAY INVISIBLE (2195 -415);
WIRE 3 2175 (2700 -1150)(3550 -1150);
WIRE 3 2175 (3550 -450)(3550 -1150);
WIRE 3 2175 (2700 -450)(2700 -1150);
WIRE 3 2175 (2700 -450)(3550 -450);
WIRE 16 -1 (4575 125)(4575 225);
WIRE 16 -1 (2275 225)(4575 225);
FORCEPROP 0 LAST VOLTAGE 3.6
J 0
(2350 300);
DISPLAY 1.021277 (2350 300);
PAINT SKYBLUE (2350 300);
DISPLAY INVISIBLE (2350 300);
FORCEPROP 2 LAST SIG_NAME VR_PVDDQ_DEF_PH2_OCSET
J 0
(2382 241);
DISPLAY 0.617021 (2382 241);
PAINT ORANGE (2382 241);
FORCEPROP 2 LASTPROP $XRERR UNIQUE?
J 0
(2142 241);
DISPLAY 0.638298 (2142 241);
PAINT MONO (2142 241);
DISPLAY INVISIBLE (2142 241);
WIRE 16 -1 (750 1775)(1250 1775);
WIRE 16 -1 (750 1625)(750 1775);
WIRE 16 -1 (-1100 1625)(-1100 1675);
WIRE 16 -1 (-1100 1625)(750 1625);
FORCEPROP 2 LAST SIG_NAME VR_PVDDQ_DEF_PH1_PHASE
J 0
(-1065 1635);
DISPLAY 0.617021 (-1065 1635);
PAINT ORANGE (-1065 1635);
FORCEPROP 2 LASTPROP $XRERR UNIQUE?
J 0
(-1305 1635);
DISPLAY 0.638298 (-1305 1635);
PAINT MONO (-1305 1635);
DISPLAY INVISIBLE (-1305 1635);
WIRE 16 -1 (-1100 1900)(-1100 1875);
WIRE 16 -1 (-1100 1900)(-225 1900);
FORCEPROP 2 LAST SIG_NAME VR_PVDDQ_DEF_PH1_BOOT
J 0
(-1090 1910);
DISPLAY 0.617021 (-1090 1910);
PAINT ORANGE (-1090 1910);
FORCEPROP 2 LASTPROP $XRERR UNIQUE?
J 0
(-1330 1910);
DISPLAY 0.638298 (-1330 1910);
PAINT MONO (-1330 1910);
DISPLAY INVISIBLE (-1330 1910);
WIRE 16 -1 (300 -75)(1275 -75);
FORCEPROP 0 LAST SIG_NAME TP_PVDDQ_DEF_PH2_GL_1
J 0
(327 -60);
DISPLAY 0.617021 (327 -60);
PAINT ORANGE (327 -60);
FORCEPROP 2 LASTPROP $XRERR UNIQUE?
J 0
(60 -75);
DISPLAY 0.638298 (60 -75);
PAINT MONO (60 -75);
DISPLAY INVISIBLE (60 -75);
WIRE 16 -1 (300 -125)(1275 -125);
FORCEPROP 0 LAST SIG_NAME TP_PVDDQ_DEF_PH2_GL_0
J 0
(327 -110);
DISPLAY 0.617021 (327 -110);
PAINT ORANGE (327 -110);
FORCEPROP 2 LASTPROP $XRERR UNIQUE?
J 0
(60 -125);
DISPLAY 0.638298 (60 -125);
PAINT MONO (60 -125);
DISPLAY INVISIBLE (60 -125);
WIRE 16 -1 (875 -475)(1275 -475);
WIRE 16 -1 (875 -675)(875 -475);
WIRE 16 -1 (-800 -675)(-800 -625);
WIRE 16 -1 (-800 -675)(875 -675);
FORCEPROP 2 LAST SIG_NAME VR_PVDDQ_DEF_PH2_PHASE
J 0
(-740 -665);
DISPLAY 0.617021 (-740 -665);
PAINT ORANGE (-740 -665);
FORCEPROP 2 LASTPROP $XRERR UNIQUE?
J 0
(-980 -665);
DISPLAY 0.638298 (-980 -665);
PAINT MONO (-980 -665);
DISPLAY INVISIBLE (-980 -665);
WIRE 16 -1 (2875 -750)(2875 -800);
WIRE 16 -1 (2875 -700)(2875 -750);
WIRE 16 -1 (2875 -750)(3500 -750);
FORCEPROP 2 LAST SIG_NAME VR_PVDDQ_DEF_PH2_SW_RC
J 0
(2935 -740);
DISPLAY 0.617021 (2935 -740);
PAINT ORANGE (2935 -740);
FORCEPROP 2 LASTPROP $XRERR UNIQUE?
J 0
(3530 -750);
DISPLAY 0.638298 (3530 -750);
PAINT MONO (3530 -750);
DISPLAY INVISIBLE (3530 -750);
WIRE 16 -1 (-1450 2025)(1250 2025);
WIRE 16 2175 (-550 2125)(150 2125);
WIRE 16 2175 (150 2550)(150 2125);
WIRE 16 2175 (-550 2550)(-550 2125);
WIRE 16 2175 (-550 2550)(150 2550);
WIRE 3 682 (-400 2500)(-400 2200);
WIRE 3 682 (-500 2500)(-400 2500);
WIRE 3 682 (-400 2200)(-500 2200);
WIRE 3 682 (-500 2200)(-500 2500);
WIRE 16 -1 (275 2125)(1250 2125);
FORCEPROP 0 LAST SIG_NAME TP_PVDDQ_DEF_PH1_GL_0
J 0
(302 2140);
DISPLAY 0.617021 (302 2140);
PAINT ORANGE (302 2140);
FORCEPROP 2 LASTPROP $XRERR UNIQUE?
J 0
(35 2125);
DISPLAY 0.638298 (35 2125);
PAINT MONO (35 2125);
DISPLAY INVISIBLE (35 2125);
WIRE 16 -1 (1025 1725)(1025 1925);
WIRE 16 -1 (1250 1925)(1025 1925);
WIRE 16 -1 (1025 1925)(1025 3000);
WIRE 16 -1 (3775 3000)(1025 3000);
FORCEPROP 2 LAST SIG_NAME VR_PVDDQ_DEF_AIREF1
J 0
(3060 3014);
DISPLAY 0.617021 (3060 3014);
PAINT ORANGE (3060 3014);
WIRE 16 -1 (2275 425)(3500 425);
FORCEPROP 2 LAST SIG_NAME ISENSE_PVDDQ_DEF_PH2_IMON
J 0
(2662 435);
DISPLAY 0.617021 (2662 435);
PAINT ORANGE (2662 435);
WIRE 3 682 (2350 175)(2450 175);
WIRE 3 2175 (2750 1800)(3500 1800);
WIRE 3 2175 (3500 1800)(3500 1125);
WIRE 3 2175 (2750 1800)(2750 1125);
WIRE 3 2175 (2750 1125)(3500 1125);
WIRE 16 -1 (2850 1500)(2850 1450);
WIRE 16 -1 (2850 1525)(2850 1500);
WIRE 16 -1 (3425 1500)(2850 1500);
FORCEPROP 2 LAST SIG_NAME VR_PVDDQ_DEF_PH1_SW_RC
J 0
(2960 1510);
DISPLAY 0.617021 (2960 1510);
PAINT ORANGE (2960 1510);
FORCEPROP 2 LASTPROP $XRERR UNIQUE?
J 0
(3455 1500);
DISPLAY 0.638298 (3455 1500);
PAINT MONO (3455 1500);
DISPLAY INVISIBLE (3455 1500);
WIRE 16 -1 (750 1825)(1250 1825);
WIRE 16 -1 (750 1900)(750 1825);
WIRE 16 -1 (-25 1900)(750 1900);
FORCEPROP 2 LAST SIG_NAME VR_PVDDQ_DEF_PH1_BOOT_R
J 0
(135 1910);
DISPLAY 0.617021 (135 1910);
PAINT ORANGE (135 1910);
FORCEPROP 2 LASTPROP $XRERR UNIQUE?
J 0
(-105 1910);
DISPLAY 0.638298 (-105 1910);
PAINT MONO (-105 1910);
DISPLAY INVISIBLE (-105 1910);
WIRE 16 2175 (-1475 1950)(-450 1950);
WIRE 16 2175 (-450 1950)(-450 1550);
WIRE 16 2175 (-1475 1950)(-1475 1550);
WIRE 16 2175 (-1475 1550)(-450 1550);
WIRE 16 -1 (2850 1725)(2850 1825);
WIRE 16 -1 (3700 1825)(2850 1825);
WIRE 16 -1 (2250 1825)(2850 1825);
FORCEPROP 2 LAST SIG_NAME VR_PVDDQ_DEF_PH1_SW
J 0
(2335 1835);
DISPLAY 0.617021 (2335 1835);
PAINT ORANGE (2335 1835);
FORCEPROP 2 LASTPROP $XRERR UNIQUE?
J 0
(2095 1835);
DISPLAY 0.638298 (2095 1835);
PAINT MONO (2095 1835);
DISPLAY INVISIBLE (2095 1835);
WIRE 3 2175 (2625 1900)(3200 1900);
WIRE 3 2175 (3200 2275)(3200 1900);
WIRE 3 2175 (2625 2275)(2625 1900);
WIRE 3 2175 (2625 2275)(3200 2275);
WIRE 3 2175 (-425 2000)(100 2000);
WIRE 3 2175 (100 2000)(100 1725);
WIRE 3 2175 (-425 2000)(-425 1725);
WIRE 3 2175 (-425 1725)(100 1725);
WIRE 3 2175 (-900 2850)(-550 2850);
WIRE 3 2175 (-550 3100)(-550 2850);
WIRE 3 2175 (-900 3100)(-900 2850);
WIRE 3 2175 (-900 3100)(-550 3100);
WIRE 16 -1 (2900 2225)(2900 2300);
WIRE 16 -1 (2900 2300)(3375 2300);
WIRE 16 -1 (2250 2300)(2250 2175);
WIRE 16 -1 (2250 2300)(2900 2300);
FORCEPROP 2 LAST SIG_NAME A_TSENSE_PVDDQ_DEF
J 0
(2287 2310);
DISPLAY 0.617021 (2287 2310);
PAINT ORANGE (2287 2310);
WIRE 3 682 (2300 2425)(2400 2425);
WIRE 16 -1 (2250 2675)(3750 2675);
FORCEPROP 2 LAST SIG_NAME ISENSE_PVDDQ_DEF_PH1_IMON
J 0
(2637 2685);
DISPLAY 0.617021 (2637 2685);
PAINT ORANGE (2637 2685);
WIRE 16 -1 (275 2175)(1250 2175);
FORCEPROP 0 LAST SIG_NAME TP_PVDDQ_DEF_PH1_GL_1
J 0
(302 2190);
DISPLAY 0.617021 (302 2190);
PAINT ORANGE (302 2190);
FORCEPROP 2 LASTPROP $XRERR UNIQUE?
J 0
(35 2175);
DISPLAY 0.638298 (35 2175);
PAINT MONO (35 2175);
DISPLAY INVISIBLE (35 2175);
DOT 1 (-1525 -150);
DOT 1 (-1250 325);
DOT 1 (-1250 -150);
DOT 1 (-1975 -150);
DOT 1 (-2200 -150);
DOT 1 (-1750 325);
DOT 1 (-925 -150);
DOT 1 (-1525 325);
DOT 1 (4350 1825);
DOT 1 (4450 1825);
DOT 1 (2850 1500);
DOT 1 (2850 1825);
DOT 1 (-125 3000);
DOT 1 (-2225 2100);
DOT 1 (-1800 2575);
DOT 1 (1025 1925);
DOT 1 (225 3000);
DOT 1 (1100 2575);
DOT 1 (2900 2300);
DOT 1 (-1175 2575);
DOT 1 (-2000 2575);
DOT 1 (-2000 2100);
DOT 1 (-1475 2100);
DOT 1 (-1175 2100);
DOT 1 (-1775 2575);
DOT 1 (-1775 2100);
DOT 1 (-1475 2575);
DOT 1 (-875 2675);
DOT 1 (-450 3000);
DOT 1 (-450 2100);
DOT 1 (2300 1625);
DOT 1 (2300 1675);
DOT 1 (2300 1575);
DOT 1 (1150 2475);
DOT 1 (3075 75);
DOT 1 (1150 225);
DOT 1 (925 325);
DOT 1 (300 700);
DOT 1 (4500 -425);
DOT 1 (4400 -425);
DOT 1 (2875 -425);
DOT 1 (2875 -750);
DOT 1 (2325 -575);
DOT 1 (2325 -625);
DOT 1 (2325 -675);
DOT 1 (1075 -325);
DOT 1 (-100 700);
DOT 1 (-525 700);
DOT 1 (-925 425);
DOT 1 (-1975 325);
DOT 1 (-525 -150);
DOT 1 (-1750 -150);
DOT 1 (-875 2100);
FORCENOTE
TP FAB4 POP CAP ON SS BOM 20170208
(-2325 -300) 0;
DISPLAY LEFT (-2325 -300);
DISPLAY 0.638298 (-2325 -300);
PAINT RED (-2325 -300);
FORCENOTE
TP FAB1 CHANGE PN 0310
(-700 325) 0;
DISPLAY LEFT (-700 325);
DISPLAY 1.021277 (-700 325);
PAINT RED (-700 325);
FORCENOTE
PLACE ON TOP
(-530 -225) 0;
DISPLAY LEFT (-530 -225);
DISPLAY 1.553191 (-530 -225);
PAINT PURPLE (-530 -225);
FORCENOTE
TDA21470
(1600 2750) 0;
DISPLAY LEFT (1600 2750);
DISPLAY 1.021277 (1600 2750);
PAINT SKYBLUE (1600 2750);
FORCENOTE
TP FAB1 DEL NET 0309
(2450 2400) 0;
DISPLAY LEFT (2450 2400);
DISPLAY 1.021277 (2450 2400);
PAINT RED (2450 2400);
FORCENOTE
TP FAB1 CHANGE TO 0 OHM 0107
(-900 3100) 0;
DISPLAY LEFT (-900 3100);
DISPLAY 0.638298 (-900 3100);
PAINT RED (-900 3100);
FORCENOTE
TP FAB1 CHANGE PN 0310
(-525 2600) 0;
DISPLAY LEFT (-525 2600);
DISPLAY 1.021277 (-525 2600);
PAINT RED (-525 2600);
FORCENOTE
PLACE ON TOP
(-530 2025) 0;
DISPLAY LEFT (-530 2025);
DISPLAY 1.553191 (-530 2025);
PAINT PURPLE (-530 2025);
FORCENOTE
SPOF
(-1180 1450) 0;
DISPLAY LEFT (-1180 1450);
DISPLAY 1.936170 (-1180 1450);
PAINT PURPLE (-1180 1450);
FORCENOTE
TP FAB1 CO-LAY WITH TI PARTS 11/16
(3250 2200) 0;
DISPLAY LEFT (3250 2200);
DISPLAY 0.553191 (3250 2200);
PAINT RED (3250 2200);
FORCENOTE
TP FAB1 CHANGE L7A1 PN 0122
(3550 2125) 0;
DISPLAY LEFT (3550 2125);
DISPLAY 0.638298 (3550 2125);
PAINT RED (3550 2125);
FORCENOTE
TP FAB3 CHANGE L7A1 0823
(3550 2075) 0;
DISPLAY LEFT (3550 2075);
DISPLAY 0.638298 (3550 2075);
PAINT RED (3550 2075);
FORCENOTE
ROOM = VDDQ_DEF_PWR_VR
(-2430 -1525) 0;
DISPLAY LEFT (-2430 -1525);
DISPLAY 2.893617 (-2430 -1525);
PAINT PURPLE (-2430 -1525);
FORCENOTE
TP FAB1 ADD NET NAME 12/04
(3050 1450) 0;
DISPLAY LEFT (3050 1450);
DISPLAY 0.638298 (3050 1450);
PAINT RED (3050 1450);
FORCENOTE
TP FAB1 CHANGE RES TO 1 OHM 0603 0107
(2750 1050) 0;
DISPLAY LEFT (2750 1050);
DISPLAY 0.638298 (2750 1050);
PAINT RED (2750 1050);
FORCENOTE
TP FAB1 CO-LAY WITH TI PARTS 11/16
(2750 1000) 0;
DISPLAY LEFT (2750 1000);
DISPLAY 0.702128 (2750 1000);
PAINT RED (2750 1000);
FORCENOTE
TP FAB1 CO-LAY WITH TI PARTS 11/16
(3450 -25) 0;
DISPLAY LEFT (3450 -25);
DISPLAY 0.553191 (3450 -25);
PAINT RED (3450 -25);
FORCENOTE
TP FAB1 CHANGE L7A3 PN 0122
(3550 -150) 0;
DISPLAY LEFT (3550 -150);
DISPLAY 0.638298 (3550 -150);
PAINT RED (3550 -150);
FORCENOTE
TP FAB3 CHANGE L7A3 0823
(3550 -200) 0;
DISPLAY LEFT (3550 -200);
DISPLAY 0.638298 (3550 -200);
PAINT RED (3550 -200);
FORCENOTE
TP FAB3-DVT NOPOP L7A3 IND FOR SS BOM 20161215
(3550 -250) 0;
DISPLAY LEFT (3550 -250);
DISPLAY 0.638298 (3550 -250);
PAINT RED (3550 -250);
FORCENOTE
TP FAB1 CHANGE RES TO 1 OHM 0603 0107
(2700 -1275) 0;
DISPLAY LEFT (2700 -1275);
DISPLAY 0.638298 (2700 -1275);
PAINT RED (2700 -1275);
FORCENOTE
SPOF
(-905 -850) 0;
DISPLAY LEFT (-905 -850);
DISPLAY 1.808511 (-905 -850);
PAINT PURPLE (-905 -850);
FORCENOTE
TP FAB1 CO-LAY WITH TI PARTS 11/16
(2700 -1200) 0;
DISPLAY LEFT (2700 -1200);
DISPLAY 0.702128 (2700 -1200);
PAINT RED (2700 -1200);
FORCENOTE
TP FAB1 ADD NET NAME 12/04
(3050 -800) 0;
DISPLAY LEFT (3050 -800);
DISPLAY 0.638298 (3050 -800);
PAINT RED (3050 -800);
FORCENOTE
TP FAB3-DVT CHANGE L7A1 IND FOR SS BOM 20161215
(3550 2025) 0;
DISPLAY LEFT (3550 2025);
DISPLAY 0.638298 (3550 2025);
PAINT RED (3550 2025);
FORCENOTE
TP FAB1 CO-LAY WITH TI PARTS 11/16
(-125 -775) 0;
DISPLAY LEFT (-125 -775);
DISPLAY 0.851064 (-125 -775);
PAINT RED (-125 -775);
FORCENOTE
TP FAB1 CO-LAY WITH TI PARTS 11/16
(-425 1475) 0;
DISPLAY LEFT (-425 1475);
DISPLAY 0.851064 (-425 1475);
PAINT RED (-425 1475);
FORCENOTE
TDA21470
(1600 500) 0;
DISPLAY LEFT (1600 500);
DISPLAY 1.021277 (1600 500);
PAINT SKYBLUE (1600 500);
FORCENOTE
TP FAB1 DEL NET 0309
(2475 175) 0;
DISPLAY LEFT (2475 175);
DISPLAY 1.021277 (2475 175);
PAINT RED (2475 175);
FORCENOTE
TP FAB1 CHANGE TO 0 OHM 0107
(-975 800) 0;
DISPLAY LEFT (-975 800);
DISPLAY 0.638298 (-975 800);
PAINT RED (-975 800);
FORCENOTE
TP FAB3-DVT NOPOP FROM SS BOM 20161215
(-2350 925) 0;
DISPLAY LEFT (-2350 925);
DISPLAY 0.638298 (-2350 925);
PAINT RED (-2350 925);
QUIT
